FILE_TYPE = MACRO_DRAWING;
SET COLOR_WIRE YELLOW;
SET COLOR_PROP MONO;
SET COLOR_DOT WHITE;
SET COLOR_ARC YELLOW;
SET COLOR_BODY GREEN;
SET COLOR_NOTE MONO;
SET PROP_DISPLAY VALUE;
SET PAGE_NUMBER P235;
FORCEADD P3V3_STBY..1
(-8375 5375);
FORCEPROP 3 LASTPIN (-8375 5325) SIG_NAME P3V3_STBY\g
J 0
(-8365 5335);
DISPLAY 0.659574 (-8365 5335);
PAINT MONO (-8365 5335);
DISPLAY INVISIBLE (-8365 5335);
FORCEPROP 1 LAST HDL_POWER P3V3_STBY
J 0
(-8675 5250);
DISPLAY 0.872340 (-8675 5250);
PAINT ORANGE (-8675 5250);
DISPLAY INVISIBLE (-8675 5250);
FORCEPROP 1 LAST VOLTAGE 3.3V
J 0
(-8420 5332);
DISPLAY 0.340426 (-8420 5332);
PAINT SKYBLUE (-8420 5332);
DISPLAY INVISIBLE (-8420 5332);
FORCEPROP 1 LAST BODY_TYPE PLUMBING
J 0
(-8420 5332);
DISPLAY 0.340426 (-8420 5332);
PAINT GREEN (-8420 5332);
DISPLAY INVISIBLE (-8420 5332);
FORCEPROP 2 LAST CDS_LIB mstr_symbols
J 0
(-8375 5375);
PAINT ORANGE (-8375 5375);
DISPLAY INVISIBLE (-8375 5375);
FORCEPROP 1 LAST PATH I135
J 0
(-8330 5377);
DISPLAY 0.340426 (-8330 5377);
PAINT GREEN (-8330 5377);
DISPLAY INVISIBLE (-8330 5377);
FORCEPROP 1 LAST SIZE 1B
J 0
(-8330 5397);
DISPLAY 0.340426 (-8330 5397);
PAINT GREEN (-8330 5397);
DISPLAY INVISIBLE (-8330 5397);
FORCEADD OFFPAGE..2
(-6275 4500);
FORCEPROP 2 LAST $XR0 190 
J 0
(-6086 4500);
DISPLAY 0.638298 (-6086 4500);
PAINT MONO (-6086 4500);
FORCEPROP 2 LAST ROOM PVNN_PCH_STBY
J 0
(-6700 4575);
DISPLAY 1.361702 (-6700 4575);
PAINT ORANGE (-6700 4575);
DISPLAY INVISIBLE (-6700 4575);
FORCEPROP 1 LAST COMMENT_BODY TRUE
J 0
(-6320 4405);
DISPLAY 1.170213 (-6320 4405);
PAINT GREEN (-6320 4405);
DISPLAY INVISIBLE (-6320 4405);
FORCEPROP 2 LAST CDS_LIB mstr_standard
J 0
(-6275 4500);
PAINT ORANGE (-6275 4500);
DISPLAY INVISIBLE (-6275 4500);
FORCEPROP 2 LAST PATH I136
J 0
(-6100 4575);
DISPLAY 1.021277 (-6100 4575);
PAINT ORANGE (-6100 4575);
DISPLAY INVISIBLE (-6100 4575);
FORCEPROP 1 LAST OFFPAGE TRUE
J 0
(-5950 4375);
DISPLAY 1.170213 (-5950 4375);
PAINT GREEN (-5950 4375);
DISPLAY INVISIBLE (-5950 4375);
FORCEADD OFFPAGE..2
(-7125 3900);
FORCEPROP 2 LAST $XR0 236 
J 0
(-6936 3900);
DISPLAY 0.638298 (-6936 3900);
PAINT MONO (-6936 3900);
FORCEPROP 2 LAST ROOM PVNN_PCH_STBY
J 0
(-7550 3975);
DISPLAY 1.361702 (-7550 3975);
PAINT ORANGE (-7550 3975);
DISPLAY INVISIBLE (-7550 3975);
FORCEPROP 1 LAST COMMENT_BODY TRUE
J 0
(-7170 3805);
DISPLAY 1.170213 (-7170 3805);
PAINT GREEN (-7170 3805);
DISPLAY INVISIBLE (-7170 3805);
FORCEPROP 2 LAST CDS_LIB mstr_standard
J 0
(-7125 3900);
PAINT ORANGE (-7125 3900);
DISPLAY INVISIBLE (-7125 3900);
FORCEPROP 2 LAST PATH I139
J 0
(-6925 3950);
DISPLAY 1.021277 (-6925 3950);
PAINT ORANGE (-6925 3950);
DISPLAY INVISIBLE (-6925 3950);
FORCEPROP 1 LAST OFFPAGE TRUE
J 0
(-6800 3775);
DISPLAY 1.170213 (-6800 3775);
PAINT GREEN (-6800 3775);
DISPLAY INVISIBLE (-6800 3775);
FORCEADD OFFPAGE..1
R 2
(-8100 2150);
FORCEPROP 2 LAST $XR0 235 
J 0
(-7914 2150);
DISPLAY 0.638298 (-7914 2150);
PAINT MONO (-7914 2150);
FORCEPROP 1 LAST OFFPAGE TRUE
J 2
(-8425 2025);
DISPLAY 1.170213 (-8425 2025);
PAINT GREEN (-8425 2025);
DISPLAY INVISIBLE (-8425 2025);
FORCEPROP 1 LAST COMMENT_BODY TRUE
J 2
(-8225 2050);
DISPLAY 1.170213 (-8225 2050);
PAINT GREEN (-8225 2050);
DISPLAY INVISIBLE (-8225 2050);
FORCEPROP 2 LAST ROOM PVNN_PCH_STBY
J 0
(-8525 2225);
DISPLAY 1.361702 (-8525 2225);
PAINT ORANGE (-8525 2225);
DISPLAY INVISIBLE (-8525 2225);
FORCEPROP 2 LAST CDS_LIB mstr_standard
J 2
(-8100 2150);
PAINT ORANGE (-8100 2150);
DISPLAY INVISIBLE (-8100 2150);
FORCEPROP 2 LAST PATH I142
J 0
(-7775 2200);
DISPLAY 1.021277 (-7775 2200);
PAINT ORANGE (-7775 2200);
DISPLAY INVISIBLE (-7775 2200);
FORCEADD CAP_A..1
(-8800 1925);
FORCEPROP 1 LASTPIN (-8800 1825) $PN 2
J 0
(-8790 1805);
DISPLAY 0.617021 (-8790 1805);
PAINT ORANGE (-8790 1805);
FORCEPROP 1 LASTPIN (-8800 2025) $PN 1
J 0
(-8790 2005);
DISPLAY 0.617021 (-8790 2005);
PAINT ORANGE (-8790 2005);
FORCEPROP 1 LAST MATERIAL X6S
J 0
(-8750 1825);
DISPLAY 0.617021 (-8750 1825);
PAINT SKYBLUE (-8750 1825);
FORCEPROP 1 LAST VOLTAGE 6.3V
J 0
(-8750 1925);
DISPLAY 0.617021 (-8750 1925);
PAINT SKYBLUE (-8750 1925);
FORCEPROP 1 LAST PACK_TYPE 0402V
J 0
(-8750 1725);
DISPLAY 0.617021 (-8750 1725);
PAINT SKYBLUE (-8750 1725);
FORCEPROP 1 LAST TOLERANCE 10%
J 0
(-8750 1875);
DISPLAY 0.617021 (-8750 1875);
PAINT SKYBLUE (-8750 1875);
FORCEPROP 1 LAST VALUE 1.0UF
J 0
(-8750 1975);
DISPLAY 0.617021 (-8750 1975);
PAINT SKYBLUE (-8750 1975);
FORCEPROP 1 LAST PART_NUMBER D97712-004
J 0
(-8750 1775);
DISPLAY 0.617021 (-8750 1775);
PAINT BLUE (-8750 1775);
FORCEPROP 1 LAST LOCATION C8A7
J 0
(-8750 2025);
DISPLAY 0.617021 (-8750 2025);
PAINT AQUA (-8750 2025);
FORCEPROP 2 LAST CDS_LIB dev_discrete
J 0
(-8800 1925);
PAINT ORANGE (-8800 1925);
DISPLAY INVISIBLE (-8800 1925);
FORCEPROP 2 LAST CDS_LOCATION C8A7
J 0
(-8750 2025);
DISPLAY 0.617021 (-8750 2025);
PAINT AQUA (-8750 2025);
DISPLAY INVISIBLE (-8750 2025);
FORCEPROP 2 LAST CDS_SEC 1
J 0
(-8750 2075);
PAINT ORANGE (-8750 2075);
DISPLAY INVISIBLE (-8750 2075);
FORCEPROP 2 LAST SEC_TYPE 0402V
J 0
(-8750 2125);
DISPLAY 1.021277 (-8750 2125);
PAINT ORANGE (-8750 2125);
DISPLAY INVISIBLE (-8750 2125);
FORCEPROP 2 LAST SEC 1
J 0
(-8750 2125);
DISPLAY 0.680851 (-8750 2125);
PAINT MONO (-8750 2125);
DISPLAY INVISIBLE (-8750 2125);
FORCEPROP 1 LAST PATH I143
J 0
(-8750 2075);
DISPLAY 0.978723 (-8750 2075);
PAINT WHITE (-8750 2075);
DISPLAY INVISIBLE (-8750 2075);
FORCEPROP 2 LAST ROOM PVNN_PCH_STBY
J 0
(-8750 2075);
DISPLAY 1.361702 (-8750 2075);
PAINT ORANGE (-8750 2075);
DISPLAY INVISIBLE (-8750 2075);
FORCEADD GND..1
(-8800 1550);
FORCEPROP 3 LASTPIN (-8800 1600) SIG_NAME GND\g
J 0
(-8790 1610);
DISPLAY 0.659574 (-8790 1610);
PAINT MONO (-8790 1610);
DISPLAY INVISIBLE (-8790 1610);
FORCEPROP 2 LAST ROOM PVNN_PCH_STBY
J 0
(-9375 1625);
DISPLAY 1.361702 (-9375 1625);
PAINT ORANGE (-9375 1625);
DISPLAY INVISIBLE (-9375 1625);
FORCEPROP 1 LAST BODY_TYPE PLUMBING
J 0
(-8845 1507);
DISPLAY 0.340426 (-8845 1507);
PAINT GREEN (-8845 1507);
DISPLAY INVISIBLE (-8845 1507);
FORCEPROP 1 LAST SIZE 1B
J 0
(-8725 1500);
DISPLAY 1.170213 (-8725 1500);
PAINT AQUA (-8725 1500);
DISPLAY INVISIBLE (-8725 1500);
FORCEPROP 1 LAST HDL_POWER GND
J 0
(-8800 1700);
DISPLAY 1.170213 (-8800 1700);
PAINT GREEN (-8800 1700);
DISPLAY INVISIBLE (-8800 1700);
FORCEPROP 1 LAST PATH I144
J 0
(-8725 1550);
DISPLAY 0.872340 (-8725 1550);
PAINT AQUA (-8725 1550);
DISPLAY INVISIBLE (-8725 1550);
FORCEPROP 1 LAST VOLTAGE 0
J 0
(-8800 1550);
PAINT SKYBLUE (-8800 1550);
DISPLAY INVISIBLE (-8800 1550);
FORCEPROP 2 LAST CDS_LIB mstr_symbols
J 0
(-8800 1550);
PAINT ORANGE (-8800 1550);
DISPLAY INVISIBLE (-8800 1550);
FORCEADD CAP_A..1
(-9200 1975);
FORCEPROP 1 LAST PACK_TYPE 0402V
J 0
(-9150 1775);
DISPLAY 0.617021 (-9150 1775);
PAINT SKYBLUE (-9150 1775);
FORCEPROP 1 LASTPIN (-9200 1875) $PN 2
J 0
(-9190 1855);
DISPLAY 0.617021 (-9190 1855);
PAINT ORANGE (-9190 1855);
FORCEPROP 1 LAST MATERIAL X7R
J 0
(-9150 1875);
DISPLAY 0.617021 (-9150 1875);
PAINT SKYBLUE (-9150 1875);
FORCEPROP 1 LAST VOLTAGE 16V
J 0
(-9150 1975);
DISPLAY 0.617021 (-9150 1975);
PAINT SKYBLUE (-9150 1975);
FORCEPROP 1 LAST TOLERANCE 10%
J 0
(-9150 1925);
DISPLAY 0.617021 (-9150 1925);
PAINT SKYBLUE (-9150 1925);
FORCEPROP 1 LAST PART_NUMBER A36096-030
J 0
(-9150 1825);
DISPLAY 0.617021 (-9150 1825);
PAINT BLUE (-9150 1825);
FORCEPROP 1 LAST VALUE 0.1UF
J 0
(-9150 2025);
DISPLAY 0.617021 (-9150 2025);
PAINT SKYBLUE (-9150 2025);
FORCEPROP 1 LAST LOCATION C8A8
J 0
(-9150 2075);
DISPLAY 0.617021 (-9150 2075);
PAINT AQUA (-9150 2075);
FORCEPROP 1 LASTPIN (-9200 2075) $PN 1
J 0
(-9190 2055);
DISPLAY 0.617021 (-9190 2055);
PAINT ORANGE (-9190 2055);
FORCEPROP 2 LAST CDS_LIB dev_discrete
J 0
(-9200 1975);
PAINT ORANGE (-9200 1975);
DISPLAY INVISIBLE (-9200 1975);
FORCEPROP 1 LAST PATH I145
J 0
(-9150 2125);
DISPLAY 0.978723 (-9150 2125);
PAINT WHITE (-9150 2125);
DISPLAY INVISIBLE (-9150 2125);
FORCEPROP 2 LAST ROOM PVNN_PCH_STBY
J 0
(-9150 2125);
DISPLAY 1.361702 (-9150 2125);
PAINT ORANGE (-9150 2125);
DISPLAY INVISIBLE (-9150 2125);
FORCEPROP 2 LAST CDS_LOCATION C8A8
J 0
(-9150 2075);
DISPLAY 0.617021 (-9150 2075);
PAINT AQUA (-9150 2075);
DISPLAY INVISIBLE (-9150 2075);
FORCEPROP 2 LAST CDS_SEC 1
J 0
(-9150 2125);
PAINT ORANGE (-9150 2125);
DISPLAY INVISIBLE (-9150 2125);
FORCEPROP 2 LAST SEC_TYPE 0402V
J 0
(-9150 2175);
DISPLAY 1.021277 (-9150 2175);
PAINT ORANGE (-9150 2175);
DISPLAY INVISIBLE (-9150 2175);
FORCEPROP 2 LAST SEC 1
J 0
(-9150 2175);
DISPLAY 0.680851 (-9150 2175);
PAINT MONO (-9150 2175);
DISPLAY INVISIBLE (-9150 2175);
FORCEADD GND..1
(-9200 1775);
FORCEPROP 3 LASTPIN (-9200 1825) SIG_NAME GND\g
J 0
(-9190 1835);
DISPLAY 0.659574 (-9190 1835);
PAINT MONO (-9190 1835);
DISPLAY INVISIBLE (-9190 1835);
FORCEPROP 2 LAST ROOM PVNN_PCH_STBY
J 0
(-9775 1850);
DISPLAY 1.361702 (-9775 1850);
PAINT ORANGE (-9775 1850);
DISPLAY INVISIBLE (-9775 1850);
FORCEPROP 1 LAST BODY_TYPE PLUMBING
J 0
(-9245 1732);
DISPLAY 0.340426 (-9245 1732);
PAINT GREEN (-9245 1732);
DISPLAY INVISIBLE (-9245 1732);
FORCEPROP 1 LAST SIZE 1B
J 0
(-9125 1725);
DISPLAY 1.170213 (-9125 1725);
PAINT AQUA (-9125 1725);
DISPLAY INVISIBLE (-9125 1725);
FORCEPROP 1 LAST VOLTAGE 0
J 0
(-9200 1775);
PAINT SKYBLUE (-9200 1775);
DISPLAY INVISIBLE (-9200 1775);
FORCEPROP 2 LAST CDS_LIB mstr_symbols
J 0
(-9200 1775);
PAINT ORANGE (-9200 1775);
DISPLAY INVISIBLE (-9200 1775);
FORCEPROP 1 LAST PATH I146
J 0
(-9125 1775);
DISPLAY 0.872340 (-9125 1775);
PAINT AQUA (-9125 1775);
DISPLAY INVISIBLE (-9125 1775);
FORCEPROP 1 LAST HDL_POWER GND
J 0
(-9200 1925);
DISPLAY 1.170213 (-9200 1925);
PAINT GREEN (-9200 1925);
DISPLAY INVISIBLE (-9200 1925);
FORCEADD RES..1
(-7100 4500);
FORCEPROP 1 LASTPIN (-7200 4500) $PN 1
J 0
(-7188 4512);
DISPLAY 0.617021 (-7188 4512);
PAINT ORANGE (-7188 4512);
FORCEPROP 1 LAST WATTAGE 1/16W
J 2
(-7125 4350);
DISPLAY 0.617021 (-7125 4350);
PAINT SKYBLUE (-7125 4350);
FORCEPROP 1 LAST VALUE 22.1
J 2
(-7125 4400);
DISPLAY 0.617021 (-7125 4400);
PAINT SKYBLUE (-7125 4400);
FORCEPROP 1 LAST PACK_TYPE 0402
J 0
(-7150 4300);
DISPLAY 0.617021 (-7150 4300);
PAINT SKYBLUE (-7150 4300);
FORCEPROP 1 LAST MATERIAL CHIP
J 0
(-7100 4350);
DISPLAY 0.617021 (-7100 4350);
PAINT SKYBLUE (-7100 4350);
FORCEPROP 1 LASTPIN (-7000 4500) $PN 2
J 0
(-7038 4512);
DISPLAY 0.617021 (-7038 4512);
PAINT ORANGE (-7038 4512);
FORCEPROP 1 LAST TOLERANCE 1.0%
J 0
(-7100 4400);
DISPLAY 0.617021 (-7100 4400);
PAINT SKYBLUE (-7100 4400);
FORCEPROP 1 LAST LOCATION R2L16
J 0
(-7150 4550);
DISPLAY 0.617021 (-7150 4550);
PAINT AQUA (-7150 4550);
FORCEPROP 1 LAST PART_NUMBER G21796-250
J 0
(-7150 4600);
DISPLAY 0.617021 (-7150 4600);
PAINT BLUE (-7150 4600);
FORCEPROP 2 LAST CDS_LIB mstr_discrete
J 0
(-7100 4500);
PAINT MONO (-7100 4500);
DISPLAY INVISIBLE (-7100 4500);
FORCEPROP 2 LAST CDS_LOCATION R2L16
J 0
(-7150 4550);
DISPLAY 0.617021 (-7150 4550);
PAINT AQUA (-7150 4550);
DISPLAY INVISIBLE (-7150 4550);
FORCEPROP 2 LAST ROOM PVNN_PCH_STBY
J 0
(-7150 4600);
DISPLAY 1.361702 (-7150 4600);
PAINT ORANGE (-7150 4600);
DISPLAY INVISIBLE (-7150 4600);
FORCEPROP 2 LAST SEC_TYPE 0402
J 0
(-7150 4700);
DISPLAY 1.021277 (-7150 4700);
PAINT ORANGE (-7150 4700);
DISPLAY INVISIBLE (-7150 4700);
FORCEPROP 2 LAST SEC 1
J 0
(-7150 4700);
DISPLAY 0.680851 (-7150 4700);
PAINT MONO (-7150 4700);
DISPLAY INVISIBLE (-7150 4700);
FORCEPROP 1 LAST PATH I147
J 0
(-7150 4650);
DISPLAY 0.978723 (-7150 4650);
PAINT WHITE (-7150 4650);
DISPLAY INVISIBLE (-7150 4650);
FORCEADD RES..2
(-8525 4800);
FORCEPROP 1 LASTPIN (-8525 4700) $PN 2
J 0
(-8520 4710);
DISPLAY 0.617021 (-8520 4710);
PAINT ORANGE (-8520 4710);
FORCEPROP 1 LASTPIN (-8525 4900) $PN 1
J 0
(-8520 4862);
DISPLAY 0.617021 (-8520 4862);
PAINT ORANGE (-8520 4862);
FORCEPROP 1 LAST WATTAGE 1/16W
J 0
(-8485 4775);
DISPLAY 0.617021 (-8485 4775);
PAINT SKYBLUE (-8485 4775);
FORCEPROP 1 LAST PACK_TYPE 0402
J 0
(-8485 4625);
DISPLAY 0.617021 (-8485 4625);
PAINT SKYBLUE (-8485 4625);
FORCEPROP 1 LAST TOLERANCE 1.0%
J 0
(-8480 4825);
DISPLAY 0.617021 (-8480 4825);
PAINT SKYBLUE (-8480 4825);
FORCEPROP 1 LAST VALUE 2.26K
J 0
(-8480 4875);
DISPLAY 0.617021 (-8480 4875);
PAINT SKYBLUE (-8480 4875);
FORCEPROP 1 LAST PART_NUMBER G21796-311
J 0
(-8485 4675);
DISPLAY 0.617021 (-8485 4675);
PAINT BLUE (-8485 4675);
FORCEPROP 1 LAST LOCATION R2L24
J 0
(-8480 4925);
DISPLAY 0.617021 (-8480 4925);
PAINT AQUA (-8480 4925);
FORCEPROP 1 LAST MATERIAL EMPTY
J 0
(-8485 4725);
DISPLAY 0.617021 (-8485 4725);
PAINT RED (-8485 4725);
FORCEPROP 2 LAST ROOM PVNN_PCH_STBY
J 0
(-8475 4775);
DISPLAY 1.361702 (-8475 4775);
PAINT ORANGE (-8475 4775);
DISPLAY INVISIBLE (-8475 4775);
FORCEPROP 2 LAST CDS_LIB mstr_discrete
J 0
(-8525 4800);
PAINT ORANGE (-8525 4800);
DISPLAY INVISIBLE (-8525 4800);
FORCEPROP 1 LAST PATH I148
J 0
(-8475 4975);
DISPLAY 0.978723 (-8475 4975);
PAINT WHITE (-8475 4975);
DISPLAY INVISIBLE (-8475 4975);
FORCEPROP 2 LAST SEC 1
J 0
(-8475 5050);
DISPLAY 0.680851 (-8475 5050);
PAINT MONO (-8475 5050);
DISPLAY INVISIBLE (-8475 5050);
FORCEPROP 2 LAST SEC_TYPE 0402
J 0
(-8475 5050);
DISPLAY 1.021277 (-8475 5050);
PAINT ORANGE (-8475 5050);
DISPLAY INVISIBLE (-8475 5050);
FORCEADD RES..2
(-9025 4875);
FORCEPROP 1 LASTPIN (-9025 4775) $PN 2
J 0
(-9020 4785);
DISPLAY 0.617021 (-9020 4785);
PAINT ORANGE (-9020 4785);
FORCEPROP 1 LASTPIN (-9025 4975) $PN 1
J 0
(-9020 4937);
DISPLAY 0.617021 (-9020 4937);
PAINT ORANGE (-9020 4937);
FORCEPROP 1 LAST PACK_TYPE 0402
J 0
(-8985 4700);
DISPLAY 0.617021 (-8985 4700);
PAINT SKYBLUE (-8985 4700);
FORCEPROP 1 LAST TOLERANCE 1%
J 0
(-8980 4900);
DISPLAY 0.617021 (-8980 4900);
PAINT SKYBLUE (-8980 4900);
FORCEPROP 1 LAST WATTAGE 1/16W
J 0
(-8985 4850);
DISPLAY 0.617021 (-8985 4850);
PAINT SKYBLUE (-8985 4850);
FORCEPROP 1 LAST LOCATION R8A6
J 0
(-8980 5000);
DISPLAY 0.617021 (-8980 5000);
PAINT AQUA (-8980 5000);
FORCEPROP 1 LAST MATERIAL CHIP
J 0
(-8985 4800);
DISPLAY 0.617021 (-8985 4800);
PAINT SKYBLUE (-8985 4800);
FORCEPROP 1 LAST VALUE 1.00K
J 0
(-8980 4950);
DISPLAY 0.617021 (-8980 4950);
PAINT SKYBLUE (-8980 4950);
FORCEPROP 1 LAST PART_NUMBER G21796-026
J 0
(-8985 4750);
DISPLAY 0.617021 (-8985 4750);
PAINT BLUE (-8985 4750);
FORCEPROP 2 LAST CDS_LOCATION R8A6
J 0
(-8980 5000);
DISPLAY 0.617021 (-8980 5000);
PAINT AQUA (-8980 5000);
DISPLAY INVISIBLE (-8980 5000);
FORCEPROP 2 LAST CDS_LIB mstr_discrete
J 0
(-9025 4875);
PAINT ORANGE (-9025 4875);
DISPLAY INVISIBLE (-9025 4875);
FORCEPROP 0 LAST SEC 1
J 0
(-8975 5050);
DISPLAY 0.680851 (-8975 5050);
PAINT MONO (-8975 5050);
DISPLAY INVISIBLE (-8975 5050);
FORCEPROP 1 LAST PATH I149
J 0
(-8975 5050);
DISPLAY 0.978723 (-8975 5050);
PAINT WHITE (-8975 5050);
DISPLAY INVISIBLE (-8975 5050);
FORCEPROP 2 LAST ROOM PVNN_PCH_STBY
J 0
(-8975 5050);
DISPLAY 1.361702 (-8975 5050);
PAINT ORANGE (-8975 5050);
DISPLAY INVISIBLE (-8975 5050);
FORCEPROP 2 LAST SEC_TYPE 0402
J 0
(-8975 5100);
DISPLAY 1.021277 (-8975 5100);
PAINT ORANGE (-8975 5100);
DISPLAY INVISIBLE (-8975 5100);
FORCEADD CAP_A..1
(-9750 5075);
FORCEPROP 1 LASTPIN (-9750 4975) $PN 2
J 0
(-9740 4955);
DISPLAY 0.617021 (-9740 4955);
PAINT ORANGE (-9740 4955);
FORCEPROP 1 LAST MATERIAL X6S
J 0
(-9700 4975);
DISPLAY 0.617021 (-9700 4975);
PAINT SKYBLUE (-9700 4975);
FORCEPROP 1 LAST VOLTAGE 6.3V
J 0
(-9700 5075);
DISPLAY 0.617021 (-9700 5075);
PAINT SKYBLUE (-9700 5075);
FORCEPROP 1 LAST PACK_TYPE 0402V
J 0
(-9700 4875);
DISPLAY 0.617021 (-9700 4875);
PAINT SKYBLUE (-9700 4875);
FORCEPROP 1 LAST TOLERANCE 10%
J 0
(-9700 5025);
DISPLAY 0.617021 (-9700 5025);
PAINT SKYBLUE (-9700 5025);
FORCEPROP 1 LAST PART_NUMBER D97712-004
J 0
(-9700 4925);
DISPLAY 0.617021 (-9700 4925);
PAINT BLUE (-9700 4925);
FORCEPROP 1 LASTPIN (-9750 5175) $PN 1
J 0
(-9740 5155);
DISPLAY 0.617021 (-9740 5155);
PAINT ORANGE (-9740 5155);
FORCEPROP 1 LAST LOCATION C2L8
J 0
(-9700 5175);
DISPLAY 0.617021 (-9700 5175);
PAINT AQUA (-9700 5175);
FORCEPROP 1 LAST VALUE 1.0UF
J 0
(-9700 5125);
DISPLAY 0.617021 (-9700 5125);
PAINT SKYBLUE (-9700 5125);
FORCEPROP 2 LAST CDS_LIB dev_discrete
J 0
(-9750 5075);
PAINT ORANGE (-9750 5075);
DISPLAY INVISIBLE (-9750 5075);
FORCEPROP 2 LAST ROOM PVNN_PCH_STBY
J 0
(-9700 5225);
DISPLAY 1.361702 (-9700 5225);
PAINT ORANGE (-9700 5225);
DISPLAY INVISIBLE (-9700 5225);
FORCEPROP 1 LAST PATH I151
J 0
(-9700 5225);
DISPLAY 0.978723 (-9700 5225);
PAINT WHITE (-9700 5225);
DISPLAY INVISIBLE (-9700 5225);
FORCEPROP 2 LAST SEC 1
J 0
(-9700 5275);
DISPLAY 0.680851 (-9700 5275);
PAINT MONO (-9700 5275);
DISPLAY INVISIBLE (-9700 5275);
FORCEPROP 2 LAST SEC_TYPE 0402V
J 0
(-9700 5275);
DISPLAY 1.021277 (-9700 5275);
PAINT ORANGE (-9700 5275);
DISPLAY INVISIBLE (-9700 5275);
FORCEPROP 2 LAST CDS_LOCATION C2L8
J 0
(-9700 5175);
DISPLAY 0.617021 (-9700 5175);
PAINT AQUA (-9700 5175);
DISPLAY INVISIBLE (-9700 5175);
FORCEPROP 2 LAST CDS_SEC 1
J 0
(-9700 5225);
PAINT ORANGE (-9700 5225);
DISPLAY INVISIBLE (-9700 5225);
FORCEADD GND..1
(-9750 4875);
FORCEPROP 3 LASTPIN (-9750 4925) SIG_NAME GND\g
J 0
(-9740 4935);
DISPLAY 0.659574 (-9740 4935);
PAINT MONO (-9740 4935);
DISPLAY INVISIBLE (-9740 4935);
FORCEPROP 2 LAST ROOM PVNN_PCH_STBY
J 0
(-10325 4950);
DISPLAY 1.361702 (-10325 4950);
PAINT ORANGE (-10325 4950);
DISPLAY INVISIBLE (-10325 4950);
FORCEPROP 1 LAST BODY_TYPE PLUMBING
J 0
(-9795 4832);
DISPLAY 0.340426 (-9795 4832);
PAINT GREEN (-9795 4832);
DISPLAY INVISIBLE (-9795 4832);
FORCEPROP 1 LAST VOLTAGE 0
J 0
(-9750 4875);
PAINT SKYBLUE (-9750 4875);
DISPLAY INVISIBLE (-9750 4875);
FORCEPROP 2 LAST CDS_LIB mstr_symbols
J 0
(-9750 4875);
PAINT ORANGE (-9750 4875);
DISPLAY INVISIBLE (-9750 4875);
FORCEPROP 1 LAST HDL_POWER GND
J 0
(-9750 5025);
DISPLAY 1.170213 (-9750 5025);
PAINT GREEN (-9750 5025);
DISPLAY INVISIBLE (-9750 5025);
FORCEPROP 1 LAST PATH I152
J 0
(-9675 4875);
DISPLAY 0.872340 (-9675 4875);
PAINT AQUA (-9675 4875);
DISPLAY INVISIBLE (-9675 4875);
FORCEPROP 1 LAST SIZE 1B
J 0
(-9675 4825);
DISPLAY 1.170213 (-9675 4825);
PAINT AQUA (-9675 4825);
DISPLAY INVISIBLE (-9675 4825);
FORCEADD CAP..1
(-12475 2075);
FORCEPROP 1 LASTPIN (-12475 1975) $PN 2
J 0
(-12465 1955);
DISPLAY 0.617021 (-12465 1955);
PAINT ORANGE (-12465 1955);
FORCEPROP 1 LASTPIN (-12475 2175) $PN 1
J 0
(-12465 2155);
DISPLAY 0.617021 (-12465 2155);
PAINT ORANGE (-12465 2155);
FORCEPROP 1 LAST LOCATION C2L2
J 0
(-12425 2175);
DISPLAY 0.617021 (-12425 2175);
PAINT AQUA (-12425 2175);
FORCEPROP 1 LAST VOLTAGE 50V
J 0
(-12425 2075);
DISPLAY 0.617021 (-12425 2075);
PAINT SKYBLUE (-12425 2075);
FORCEPROP 1 LAST MATERIAL X7R
J 0
(-12300 2075);
DISPLAY 0.617021 (-12300 2075);
PAINT SKYBLUE (-12300 2075);
FORCEPROP 1 LAST PACK_TYPE 0402LF
J 0
(-12425 1975);
DISPLAY 0.617021 (-12425 1975);
PAINT SKYBLUE (-12425 1975);
FORCEPROP 1 LAST VALUE 220PF
J 0
(-12425 2125);
DISPLAY 0.617021 (-12425 2125);
PAINT SKYBLUE (-12425 2125);
FORCEPROP 1 LAST PART_NUMBER A36096-050
J 0
(-12425 2025);
DISPLAY 0.617021 (-12425 2025);
PAINT BLUE (-12425 2025);
FORCEPROP 1 LAST TOLERANCE 10%
J 0
(-12250 2125);
DISPLAY 0.617021 (-12250 2125);
PAINT SKYBLUE (-12250 2125);
FORCEPROP 2 LAST CDS_LIB mstr_discrete
J 0
(-12475 2075);
PAINT ORANGE (-12475 2075);
DISPLAY INVISIBLE (-12475 2075);
FORCEPROP 2 LAST CDS_LOCATION C2L2
J 0
(-12425 2175);
DISPLAY 0.617021 (-12425 2175);
PAINT AQUA (-12425 2175);
DISPLAY INVISIBLE (-12425 2175);
FORCEPROP 2 LAST ROOM PVNN_PCH_STBY
J 0
(-12425 2225);
DISPLAY 1.361702 (-12425 2225);
PAINT ORANGE (-12425 2225);
DISPLAY INVISIBLE (-12425 2225);
FORCEPROP 1 LAST PATH I153
J 0
(-12425 2225);
DISPLAY 0.978723 (-12425 2225);
PAINT WHITE (-12425 2225);
DISPLAY INVISIBLE (-12425 2225);
FORCEPROP 2 LAST NO_XNET_CONNECTION 1
J 0
(-12425 2275);
PAINT MONO (-12425 2275);
DISPLAY INVISIBLE (-12425 2275);
FORCEPROP 2 LAST SEC 1
J 0
(-12425 2300);
DISPLAY 0.680851 (-12425 2300);
PAINT MONO (-12425 2300);
DISPLAY INVISIBLE (-12425 2300);
FORCEPROP 2 LAST SEC_TYPE 0402LF
J 0
(-12425 2300);
DISPLAY 1.021277 (-12425 2300);
PAINT ORANGE (-12425 2300);
DISPLAY INVISIBLE (-12425 2300);
FORCEADD RES..1
(-12675 2225);
FORCEPROP 1 LAST WATTAGE 1/10W
J 2
(-12675 2075);
DISPLAY 0.617021 (-12675 2075);
PAINT SKYBLUE (-12675 2075);
FORCEPROP 1 LAST VALUE 10.0
J 2
(-12775 2125);
DISPLAY 0.617021 (-12775 2125);
PAINT SKYBLUE (-12775 2125);
FORCEPROP 1 LAST PART_NUMBER G22026-041
J 0
(-12825 2175);
DISPLAY 0.617021 (-12825 2175);
PAINT BLUE (-12825 2175);
FORCEPROP 1 LASTPIN (-12775 2225) $PN 1
J 0
(-12763 2237);
DISPLAY 0.617021 (-12763 2237);
PAINT ORANGE (-12763 2237);
FORCEPROP 1 LAST TOLERANCE 1%
J 0
(-12750 2125);
DISPLAY 0.617021 (-12750 2125);
PAINT SKYBLUE (-12750 2125);
FORCEPROP 1 LAST LOCATION R2L8
J 0
(-12725 2275);
DISPLAY 0.617021 (-12725 2275);
PAINT AQUA (-12725 2275);
FORCEPROP 1 LASTPIN (-12575 2225) $PN 2
J 0
(-12613 2237);
DISPLAY 0.617021 (-12613 2237);
PAINT ORANGE (-12613 2237);
FORCEPROP 1 LAST MATERIAL CHIP
J 0
(-12650 2075);
DISPLAY 0.617021 (-12650 2075);
PAINT SKYBLUE (-12650 2075);
FORCEPROP 1 LAST PACK_TYPE 0603
J 0
(-12650 2125);
DISPLAY 0.617021 (-12650 2125);
PAINT SKYBLUE (-12650 2125);
FORCEPROP 2 LAST CDS_LIB mstr_discrete
J 0
(-12675 2225);
PAINT ORANGE (-12675 2225);
DISPLAY INVISIBLE (-12675 2225);
FORCEPROP 2 LAST CDS_LOCATION R2L8
J 0
(-12725 2275);
DISPLAY 0.617021 (-12725 2275);
PAINT AQUA (-12725 2275);
DISPLAY INVISIBLE (-12725 2275);
FORCEPROP 2 LAST SEC_TYPE 0603
J 0
(-12725 2450);
DISPLAY 1.021277 (-12725 2450);
PAINT ORANGE (-12725 2450);
DISPLAY INVISIBLE (-12725 2450);
FORCEPROP 2 LAST SEC 1
J 0
(-12725 2450);
DISPLAY 0.680851 (-12725 2450);
PAINT MONO (-12725 2450);
DISPLAY INVISIBLE (-12725 2450);
FORCEPROP 1 LAST PATH I154
J 0
(-12725 2375);
DISPLAY 0.978723 (-12725 2375);
PAINT WHITE (-12725 2375);
DISPLAY INVISIBLE (-12725 2375);
FORCEPROP 2 LAST ROOM PVNN_PCH_STBY
J 0
(-12600 2325);
DISPLAY 1.361702 (-12600 2325);
PAINT ORANGE (-12600 2325);
DISPLAY INVISIBLE (-12600 2325);
FORCEADD GND..1
(-8900 2800);
FORCEPROP 3 LASTPIN (-8900 2850) SIG_NAME GND\g
J 0
(-8890 2860);
DISPLAY 0.659574 (-8890 2860);
PAINT MONO (-8890 2860);
DISPLAY INVISIBLE (-8890 2860);
FORCEPROP 2 LAST ROOM PVNN_PCH_STBY
J 0
(-9475 2875);
DISPLAY 1.361702 (-9475 2875);
PAINT ORANGE (-9475 2875);
DISPLAY INVISIBLE (-9475 2875);
FORCEPROP 1 LAST BODY_TYPE PLUMBING
J 0
(-8945 2757);
DISPLAY 0.340426 (-8945 2757);
PAINT GREEN (-8945 2757);
DISPLAY INVISIBLE (-8945 2757);
FORCEPROP 1 LAST SIZE 1B
J 0
(-8825 2750);
DISPLAY 1.170213 (-8825 2750);
PAINT AQUA (-8825 2750);
DISPLAY INVISIBLE (-8825 2750);
FORCEPROP 1 LAST PATH I155
J 0
(-8825 2800);
DISPLAY 0.872340 (-8825 2800);
PAINT AQUA (-8825 2800);
DISPLAY INVISIBLE (-8825 2800);
FORCEPROP 2 LAST CDS_LIB mstr_symbols
J 0
(-8900 2800);
PAINT ORANGE (-8900 2800);
DISPLAY INVISIBLE (-8900 2800);
FORCEPROP 1 LAST VOLTAGE 0
J 0
(-8900 2800);
PAINT SKYBLUE (-8900 2800);
DISPLAY INVISIBLE (-8900 2800);
FORCEPROP 1 LAST HDL_POWER GND
J 0
(-8900 2950);
DISPLAY 1.170213 (-8900 2950);
PAINT GREEN (-8900 2950);
DISPLAY INVISIBLE (-8900 2950);
FORCEADD OFFPAGE..1
(-13350 2225);
FORCEPROP 2 LAST $XR0 236 
J 0
(-13602 2225);
DISPLAY 0.638298 (-13602 2225);
PAINT MONO (-13602 2225);
FORCEPROP 2 LAST ROOM PVNN_PCH_STBY
J 0
(-13900 2300);
DISPLAY 1.361702 (-13900 2300);
PAINT ORANGE (-13900 2300);
DISPLAY INVISIBLE (-13900 2300);
FORCEPROP 2 LAST PATH I156
J 0
(-13600 2275);
DISPLAY 1.021277 (-13600 2275);
PAINT ORANGE (-13600 2275);
DISPLAY INVISIBLE (-13600 2275);
FORCEPROP 2 LAST CDS_LIB mstr_standard
J 0
(-13350 2225);
PAINT ORANGE (-13350 2225);
DISPLAY INVISIBLE (-13350 2225);
FORCEPROP 1 LAST COMMENT_BODY TRUE
J 0
(-13225 2125);
DISPLAY 1.170213 (-13225 2125);
PAINT GREEN (-13225 2125);
DISPLAY INVISIBLE (-13225 2125);
FORCEPROP 1 LAST OFFPAGE TRUE
J 0
(-13025 2100);
DISPLAY 1.170213 (-13025 2100);
PAINT GREEN (-13025 2100);
DISPLAY INVISIBLE (-13025 2100);
FORCEADD OFFPAGE..1
(-13225 1950);
FORCEPROP 2 LAST $XR0 236 
J 0
(-13477 1950);
DISPLAY 0.638298 (-13477 1950);
PAINT MONO (-13477 1950);
FORCEPROP 2 LAST PATH I157
J 0
(-13475 2000);
DISPLAY 1.021277 (-13475 2000);
PAINT ORANGE (-13475 2000);
DISPLAY INVISIBLE (-13475 2000);
FORCEPROP 1 LAST COMMENT_BODY TRUE
J 0
(-13100 1850);
DISPLAY 1.170213 (-13100 1850);
PAINT GREEN (-13100 1850);
DISPLAY INVISIBLE (-13100 1850);
FORCEPROP 2 LAST CDS_LIB mstr_standard
J 0
(-13225 1950);
PAINT ORANGE (-13225 1950);
DISPLAY INVISIBLE (-13225 1950);
FORCEPROP 1 LAST OFFPAGE TRUE
J 0
(-12900 1825);
DISPLAY 1.170213 (-12900 1825);
PAINT GREEN (-12900 1825);
DISPLAY INVISIBLE (-12900 1825);
FORCEPROP 2 LAST ROOM PVNN_PCH_STBY
J 0
(-13775 2025);
DISPLAY 1.361702 (-13775 2025);
PAINT ORANGE (-13775 2025);
DISPLAY INVISIBLE (-13775 2025);
FORCEADD P3V3_STBY..1
(-10450 5750);
FORCEPROP 3 LASTPIN (-10450 5700) SIG_NAME P3V3_STBY\g
J 0
(-10440 5710);
DISPLAY 0.659574 (-10440 5710);
PAINT MONO (-10440 5710);
DISPLAY INVISIBLE (-10440 5710);
FORCEPROP 1 LAST HDL_POWER P3V3_STBY
J 0
(-10750 5625);
DISPLAY 0.872340 (-10750 5625);
PAINT ORANGE (-10750 5625);
DISPLAY INVISIBLE (-10750 5625);
FORCEPROP 1 LAST PATH I158
J 0
(-10405 5752);
DISPLAY 0.340426 (-10405 5752);
PAINT GREEN (-10405 5752);
DISPLAY INVISIBLE (-10405 5752);
FORCEPROP 1 LAST BODY_TYPE PLUMBING
J 0
(-10495 5707);
DISPLAY 0.340426 (-10495 5707);
PAINT GREEN (-10495 5707);
DISPLAY INVISIBLE (-10495 5707);
FORCEPROP 2 LAST CDS_LIB mstr_symbols
J 0
(-10450 5750);
PAINT ORANGE (-10450 5750);
DISPLAY INVISIBLE (-10450 5750);
FORCEPROP 1 LAST SIZE 1B
J 0
(-10405 5772);
DISPLAY 0.340426 (-10405 5772);
PAINT GREEN (-10405 5772);
DISPLAY INVISIBLE (-10405 5772);
FORCEPROP 1 LAST VOLTAGE 3.3V
J 0
(-10495 5707);
DISPLAY 0.340426 (-10495 5707);
PAINT SKYBLUE (-10495 5707);
DISPLAY INVISIBLE (-10495 5707);
FORCEADD RES..2
(-10450 5425);
FORCEPROP 1 LASTPIN (-10450 5325) $PN 2
J 0
(-10445 5335);
DISPLAY 0.617021 (-10445 5335);
PAINT ORANGE (-10445 5335);
FORCEPROP 1 LAST MATERIAL CHIP
J 0
(-10410 5350);
DISPLAY 0.617021 (-10410 5350);
PAINT SKYBLUE (-10410 5350);
FORCEPROP 1 LAST PACK_TYPE 0402
J 0
(-10410 5250);
DISPLAY 0.617021 (-10410 5250);
PAINT SKYBLUE (-10410 5250);
FORCEPROP 1 LASTPIN (-10450 5525) $PN 1
J 0
(-10445 5487);
DISPLAY 0.617021 (-10445 5487);
PAINT ORANGE (-10445 5487);
FORCEPROP 1 LAST WATTAGE 1/16W
J 0
(-10410 5400);
DISPLAY 0.617021 (-10410 5400);
PAINT SKYBLUE (-10410 5400);
FORCEPROP 1 LAST LOCATION R2L14
J 0
(-10405 5550);
DISPLAY 0.617021 (-10405 5550);
PAINT AQUA (-10405 5550);
FORCEPROP 1 LAST VALUE 0.0
J 0
(-10405 5500);
DISPLAY 0.617021 (-10405 5500);
PAINT SKYBLUE (-10405 5500);
FORCEPROP 1 LAST TOLERANCE 5%
J 0
(-10405 5450);
DISPLAY 0.617021 (-10405 5450);
PAINT SKYBLUE (-10405 5450);
FORCEPROP 1 LAST PART_NUMBER G21497-005
J 0
(-10410 5300);
DISPLAY 0.617021 (-10410 5300);
PAINT BLUE (-10410 5300);
FORCEPROP 2 LAST CDS_LIB mstr_discrete
J 0
(-10450 5425);
PAINT ORANGE (-10450 5425);
DISPLAY INVISIBLE (-10450 5425);
FORCEPROP 2 LAST CDS_LOCATION R2L14
J 0
(-10405 5550);
DISPLAY 0.617021 (-10405 5550);
PAINT AQUA (-10405 5550);
DISPLAY INVISIBLE (-10405 5550);
FORCEPROP 0 LAST SEC 1
J 0
(-10400 5600);
DISPLAY 0.680851 (-10400 5600);
PAINT MONO (-10400 5600);
DISPLAY INVISIBLE (-10400 5600);
FORCEPROP 2 LAST ROOM PVNN_PCH_STBY
J 0
(-10400 5600);
DISPLAY 1.361702 (-10400 5600);
PAINT ORANGE (-10400 5600);
DISPLAY INVISIBLE (-10400 5600);
FORCEPROP 1 LAST PATH I159
J 0
(-10400 5600);
DISPLAY 0.978723 (-10400 5600);
PAINT WHITE (-10400 5600);
DISPLAY INVISIBLE (-10400 5600);
FORCEPROP 2 LAST SEC_TYPE 0402
J 0
(-10400 5650);
DISPLAY 1.021277 (-10400 5650);
PAINT ORANGE (-10400 5650);
DISPLAY INVISIBLE (-10400 5650);
FORCEADD RES..2
(-12325 5500);
FORCEPROP 1 LAST LOCATION R8A4
J 0
(-12505 5500);
DISPLAY 0.617021 (-12505 5500);
PAINT AQUA (-12505 5500);
FORCEPROP 1 LASTPIN (-12325 5400) $PN 2
J 0
(-12320 5410);
DISPLAY 0.617021 (-12320 5410);
PAINT ORANGE (-12320 5410);
FORCEPROP 1 LASTPIN (-12325 5600) $PN 1
J 0
(-12320 5562);
DISPLAY 0.617021 (-12320 5562);
PAINT ORANGE (-12320 5562);
FORCEPROP 1 LAST WATTAGE 1/16W
J 0
(-12285 5475);
DISPLAY 0.617021 (-12285 5475);
PAINT SKYBLUE (-12285 5475);
FORCEPROP 1 LAST MATERIAL CHIP
J 0
(-12285 5425);
DISPLAY 0.617021 (-12285 5425);
PAINT SKYBLUE (-12285 5425);
FORCEPROP 1 LAST PACK_TYPE 0402
J 0
(-12285 5325);
DISPLAY 0.617021 (-12285 5325);
PAINT SKYBLUE (-12285 5325);
FORCEPROP 1 LAST TOLERANCE 1%
J 0
(-12280 5525);
DISPLAY 0.617021 (-12280 5525);
PAINT SKYBLUE (-12280 5525);
FORCEPROP 1 LAST VALUE 100.0K
J 0
(-12280 5575);
DISPLAY 0.617021 (-12280 5575);
PAINT SKYBLUE (-12280 5575);
FORCEPROP 1 LAST PART_NUMBER G21796-160
J 0
(-12285 5375);
DISPLAY 0.617021 (-12285 5375);
PAINT BLUE (-12285 5375);
FORCEPROP 2 LAST CDS_LOCATION R8A4
J 0
(-12505 5500);
DISPLAY 0.617021 (-12505 5500);
PAINT AQUA (-12505 5500);
DISPLAY INVISIBLE (-12505 5500);
FORCEPROP 2 LAST CDS_LIB mstr_discrete
J 0
(-12325 5500);
PAINT ORANGE (-12325 5500);
DISPLAY INVISIBLE (-12325 5500);
FORCEPROP 2 LAST ROOM PVNN_PCH_STBY
J 0
(-12275 5675);
DISPLAY 1.361702 (-12275 5675);
PAINT ORANGE (-12275 5675);
DISPLAY INVISIBLE (-12275 5675);
FORCEPROP 1 LAST PATH I165
J 0
(-12275 5675);
DISPLAY 0.978723 (-12275 5675);
PAINT WHITE (-12275 5675);
DISPLAY INVISIBLE (-12275 5675);
FORCEPROP 2 LAST SEC 1
J 0
(-12275 5725);
DISPLAY 0.680851 (-12275 5725);
PAINT MONO (-12275 5725);
DISPLAY INVISIBLE (-12275 5725);
FORCEPROP 2 LAST SEC_TYPE 0402
J 0
(-12275 5725);
DISPLAY 1.021277 (-12275 5725);
PAINT ORANGE (-12275 5725);
DISPLAY INVISIBLE (-12275 5725);
FORCEADD RES..2
(-12325 5175);
FORCEPROP 1 LASTPIN (-12325 5075) $PN 2
J 0
(-12320 5085);
DISPLAY 0.617021 (-12320 5085);
PAINT ORANGE (-12320 5085);
FORCEPROP 1 LAST LOCATION R2L10
J 0
(-12480 5150);
DISPLAY 0.617021 (-12480 5150);
PAINT AQUA (-12480 5150);
FORCEPROP 1 LASTPIN (-12325 5275) $PN 1
J 0
(-12320 5237);
DISPLAY 0.617021 (-12320 5237);
PAINT ORANGE (-12320 5237);
FORCEPROP 1 LAST PACK_TYPE 0402
J 0
(-12285 5000);
DISPLAY 0.617021 (-12285 5000);
PAINT SKYBLUE (-12285 5000);
FORCEPROP 1 LAST PART_NUMBER G21796-003
J 0
(-12285 5050);
DISPLAY 0.617021 (-12285 5050);
PAINT BLUE (-12285 5050);
FORCEPROP 1 LAST MATERIAL CHIP
J 0
(-12285 5100);
DISPLAY 0.617021 (-12285 5100);
PAINT SKYBLUE (-12285 5100);
FORCEPROP 1 LAST WATTAGE 1/16W
J 0
(-12285 5150);
DISPLAY 0.617021 (-12285 5150);
PAINT SKYBLUE (-12285 5150);
FORCEPROP 1 LAST TOLERANCE 1%
J 0
(-12280 5200);
DISPLAY 0.617021 (-12280 5200);
PAINT SKYBLUE (-12280 5200);
FORCEPROP 1 LAST VALUE 1.5K
J 0
(-12280 5250);
DISPLAY 0.617021 (-12280 5250);
PAINT SKYBLUE (-12280 5250);
FORCEPROP 2 LAST CDS_LOCATION R2L10
J 0
(-12480 5150);
DISPLAY 0.617021 (-12480 5150);
PAINT AQUA (-12480 5150);
DISPLAY INVISIBLE (-12480 5150);
FORCEPROP 2 LAST CDS_LIB mstr_discrete
J 0
(-12325 5175);
PAINT ORANGE (-12325 5175);
DISPLAY INVISIBLE (-12325 5175);
FORCEPROP 2 LAST ROOM PVNN_PCH_STBY
J 0
(-12275 5350);
DISPLAY 1.361702 (-12275 5350);
PAINT ORANGE (-12275 5350);
DISPLAY INVISIBLE (-12275 5350);
FORCEPROP 1 LAST PATH I166
J 0
(-12275 5350);
DISPLAY 0.978723 (-12275 5350);
PAINT WHITE (-12275 5350);
DISPLAY INVISIBLE (-12275 5350);
FORCEPROP 2 LAST SEC 1
J 0
(-12275 5400);
DISPLAY 0.680851 (-12275 5400);
PAINT MONO (-12275 5400);
DISPLAY INVISIBLE (-12275 5400);
FORCEPROP 2 LAST SEC_TYPE 0402
J 0
(-12275 5400);
DISPLAY 1.021277 (-12275 5400);
PAINT ORANGE (-12275 5400);
DISPLAY INVISIBLE (-12275 5400);
FORCEADD CAP..1
R 2
(-12550 5175);
FORCEPROP 1 LASTPIN (-12550 5075) $PN 2
J 2
(-12560 5055);
DISPLAY 0.617021 (-12560 5055);
PAINT ORANGE (-12560 5055);
FORCEPROP 1 LAST MATERIAL X7R
J 2
(-12600 5075);
DISPLAY 0.617021 (-12600 5075);
PAINT SKYBLUE (-12600 5075);
FORCEPROP 1 LAST PACK_TYPE 0402LF
J 2
(-12600 4975);
DISPLAY 0.617021 (-12600 4975);
PAINT SKYBLUE (-12600 4975);
FORCEPROP 1 LAST VOLTAGE 50V
J 2
(-12600 5175);
DISPLAY 0.617021 (-12600 5175);
PAINT SKYBLUE (-12600 5175);
FORCEPROP 1 LAST TOLERANCE 10%
J 2
(-12600 5125);
DISPLAY 0.617021 (-12600 5125);
PAINT SKYBLUE (-12600 5125);
FORCEPROP 1 LASTPIN (-12550 5275) $PN 1
J 2
(-12560 5255);
DISPLAY 0.617021 (-12560 5255);
PAINT ORANGE (-12560 5255);
FORCEPROP 1 LAST PART_NUMBER A36096-046
J 2
(-12600 5025);
DISPLAY 0.617021 (-12600 5025);
PAINT BLUE (-12600 5025);
FORCEPROP 1 LAST VALUE 1000PF
J 2
(-12600 5225);
DISPLAY 0.617021 (-12600 5225);
PAINT SKYBLUE (-12600 5225);
FORCEPROP 1 LAST LOCATION C8A3
J 2
(-12600 5275);
DISPLAY 0.617021 (-12600 5275);
PAINT AQUA (-12600 5275);
FORCEPROP 1 LAST PATH I167
J 2
(-12600 5325);
DISPLAY 0.978723 (-12600 5325);
PAINT WHITE (-12600 5325);
DISPLAY INVISIBLE (-12600 5325);
FORCEPROP 2 LAST CDS_LOCATION C8A3
J 2
(-12600 5275);
DISPLAY 0.617021 (-12600 5275);
PAINT AQUA (-12600 5275);
DISPLAY INVISIBLE (-12600 5275);
FORCEPROP 2 LAST CDS_LIB mstr_discrete
J 2
(-12550 5175);
PAINT ORANGE (-12550 5175);
DISPLAY INVISIBLE (-12550 5175);
FORCEPROP 2 LAST ROOM PVNN_PCH_STBY
J 0
(-12600 5325);
DISPLAY 1.361702 (-12600 5325);
PAINT ORANGE (-12600 5325);
DISPLAY INVISIBLE (-12600 5325);
FORCEPROP 2 LAST SEC_TYPE 0402LF
J 0
(-12600 5400);
DISPLAY 1.021277 (-12600 5400);
PAINT ORANGE (-12600 5400);
DISPLAY INVISIBLE (-12600 5400);
FORCEPROP 2 LAST SEC 1
J 0
(-12600 5400);
DISPLAY 0.680851 (-12600 5400);
PAINT MONO (-12600 5400);
DISPLAY INVISIBLE (-12600 5400);
FORCEADD OFFPAGE..2
R 2
(-13150 5350);
FORCEPROP 2 LAST $XR0 235 
J 0
(-13405 5350);
DISPLAY 0.638298 (-13405 5350);
PAINT MONO (-13405 5350);
FORCEPROP 2 LAST PATH I168
J 0
(-13425 5400);
DISPLAY 1.021277 (-13425 5400);
PAINT ORANGE (-13425 5400);
DISPLAY INVISIBLE (-13425 5400);
FORCEPROP 1 LAST OFFPAGE TRUE
J 2
(-13475 5225);
DISPLAY 1.170213 (-13475 5225);
PAINT GREEN (-13475 5225);
DISPLAY INVISIBLE (-13475 5225);
FORCEPROP 2 LAST ROOM PVNN_PCH_STBY
J 0
(-13700 5425);
DISPLAY 1.361702 (-13700 5425);
PAINT ORANGE (-13700 5425);
DISPLAY INVISIBLE (-13700 5425);
FORCEPROP 1 LAST COMMENT_BODY TRUE
J 2
(-13105 5255);
DISPLAY 1.170213 (-13105 5255);
PAINT GREEN (-13105 5255);
DISPLAY INVISIBLE (-13105 5255);
FORCEPROP 2 LAST CDS_LIB mstr_standard
J 2
(-13150 5350);
PAINT ORANGE (-13150 5350);
DISPLAY INVISIBLE (-13150 5350);
FORCEADD CAP_A..1
(-10150 5075);
FORCEPROP 1 LASTPIN (-10150 4975) $PN 2
J 0
(-10140 4955);
DISPLAY 0.617021 (-10140 4955);
PAINT ORANGE (-10140 4955);
FORCEPROP 1 LAST MATERIAL X7R
J 0
(-10100 4975);
DISPLAY 0.617021 (-10100 4975);
PAINT SKYBLUE (-10100 4975);
FORCEPROP 1 LAST VOLTAGE 16V
J 0
(-10100 5075);
DISPLAY 0.617021 (-10100 5075);
PAINT SKYBLUE (-10100 5075);
FORCEPROP 1 LAST TOLERANCE 10%
J 0
(-10100 5025);
DISPLAY 0.617021 (-10100 5025);
PAINT SKYBLUE (-10100 5025);
FORCEPROP 1 LAST PACK_TYPE 0402V
J 0
(-10100 4875);
DISPLAY 0.617021 (-10100 4875);
PAINT SKYBLUE (-10100 4875);
FORCEPROP 1 LAST PART_NUMBER A36096-030
J 0
(-10100 4925);
DISPLAY 0.617021 (-10100 4925);
PAINT BLUE (-10100 4925);
FORCEPROP 1 LASTPIN (-10150 5175) $PN 1
J 0
(-10140 5155);
DISPLAY 0.617021 (-10140 5155);
PAINT ORANGE (-10140 5155);
FORCEPROP 1 LAST LOCATION C2L11
J 0
(-10100 5175);
DISPLAY 0.617021 (-10100 5175);
PAINT AQUA (-10100 5175);
FORCEPROP 1 LAST VALUE 0.1UF
J 0
(-10100 5125);
DISPLAY 0.617021 (-10100 5125);
PAINT SKYBLUE (-10100 5125);
FORCEPROP 2 LAST CDS_LIB dev_discrete
J 0
(-10150 5075);
PAINT ORANGE (-10150 5075);
DISPLAY INVISIBLE (-10150 5075);
FORCEPROP 1 LAST PATH I169
J 0
(-10100 5225);
DISPLAY 0.978723 (-10100 5225);
PAINT WHITE (-10100 5225);
DISPLAY INVISIBLE (-10100 5225);
FORCEPROP 2 LAST ROOM PVNN_PCH_STBY
J 0
(-10100 5225);
DISPLAY 1.361702 (-10100 5225);
PAINT ORANGE (-10100 5225);
DISPLAY INVISIBLE (-10100 5225);
FORCEPROP 2 LAST CDS_LOCATION C2L11
J 0
(-10100 5175);
DISPLAY 0.617021 (-10100 5175);
PAINT AQUA (-10100 5175);
DISPLAY INVISIBLE (-10100 5175);
FORCEPROP 2 LAST CDS_SEC 1
J 0
(-10100 5225);
PAINT ORANGE (-10100 5225);
DISPLAY INVISIBLE (-10100 5225);
FORCEPROP 2 LAST SEC_TYPE 0402V
J 0
(-10100 5275);
DISPLAY 1.021277 (-10100 5275);
PAINT ORANGE (-10100 5275);
DISPLAY INVISIBLE (-10100 5275);
FORCEPROP 2 LAST SEC 1
J 0
(-10100 5225);
DISPLAY 0.680851 (-10100 5225);
PAINT MONO (-10100 5225);
DISPLAY INVISIBLE (-10100 5225);
FORCEADD GND..1
(-10150 4875);
FORCEPROP 3 LASTPIN (-10150 4925) SIG_NAME GND\g
J 0
(-10140 4935);
DISPLAY 0.659574 (-10140 4935);
PAINT MONO (-10140 4935);
DISPLAY INVISIBLE (-10140 4935);
FORCEPROP 2 LAST ROOM PVNN_PCH_STBY
J 0
(-10725 4950);
DISPLAY 1.361702 (-10725 4950);
PAINT ORANGE (-10725 4950);
DISPLAY INVISIBLE (-10725 4950);
FORCEPROP 1 LAST BODY_TYPE PLUMBING
J 0
(-10195 4832);
DISPLAY 0.340426 (-10195 4832);
PAINT GREEN (-10195 4832);
DISPLAY INVISIBLE (-10195 4832);
FORCEPROP 1 LAST SIZE 1B
J 0
(-10075 4825);
DISPLAY 1.170213 (-10075 4825);
PAINT AQUA (-10075 4825);
DISPLAY INVISIBLE (-10075 4825);
FORCEPROP 2 LAST CDS_LIB mstr_symbols
J 0
(-10150 4875);
PAINT ORANGE (-10150 4875);
DISPLAY INVISIBLE (-10150 4875);
FORCEPROP 1 LAST VOLTAGE 0
J 0
(-10150 4875);
PAINT SKYBLUE (-10150 4875);
DISPLAY INVISIBLE (-10150 4875);
FORCEPROP 1 LAST HDL_POWER GND
J 0
(-10150 5025);
DISPLAY 1.170213 (-10150 5025);
PAINT GREEN (-10150 5025);
DISPLAY INVISIBLE (-10150 5025);
FORCEPROP 1 LAST PATH I170
J 0
(-10075 4875);
DISPLAY 0.872340 (-10075 4875);
PAINT AQUA (-10075 4875);
DISPLAY INVISIBLE (-10075 4875);
FORCEADD RES..1
(-11075 3350);
FORCEPROP 1 LAST VALUE 20.0
J 2
(-11100 3250);
DISPLAY 0.617021 (-11100 3250);
PAINT SKYBLUE (-11100 3250);
FORCEPROP 1 LAST TOLERANCE 1%
J 0
(-11075 3250);
DISPLAY 0.617021 (-11075 3250);
PAINT SKYBLUE (-11075 3250);
FORCEPROP 1 LAST WATTAGE 1/16W
J 2
(-11100 3200);
DISPLAY 0.617021 (-11100 3200);
PAINT SKYBLUE (-11100 3200);
FORCEPROP 1 LAST LOCATION R8A8
J 0
(-11125 3400);
DISPLAY 0.617021 (-11125 3400);
PAINT AQUA (-11125 3400);
FORCEPROP 1 LAST MATERIAL CHIP
J 0
(-11075 3200);
DISPLAY 0.617021 (-11075 3200);
PAINT SKYBLUE (-11075 3200);
FORCEPROP 1 LAST PART_NUMBER G21796-173
J 0
(-11125 3450);
DISPLAY 0.617021 (-11125 3450);
PAINT BLUE (-11125 3450);
FORCEPROP 1 LAST PACK_TYPE 0402
J 0
(-10950 3200);
DISPLAY 0.617021 (-10950 3200);
PAINT SKYBLUE (-10950 3200);
FORCEPROP 1 LASTPIN (-11175 3350) $PN 1
J 0
(-11163 3362);
DISPLAY 0.787234 (-11163 3362);
PAINT ORANGE (-11163 3362);
DISPLAY INVISIBLE (-11163 3362);
FORCEPROP 1 LASTPIN (-10975 3350) $PN 2
J 0
(-11013 3362);
DISPLAY 0.787234 (-11013 3362);
PAINT ORANGE (-11013 3362);
DISPLAY INVISIBLE (-11013 3362);
FORCEPROP 2 LAST ROOM PVNN_PCH_STBY
J 0
(-11125 3450);
DISPLAY 1.361702 (-11125 3450);
PAINT ORANGE (-11125 3450);
DISPLAY INVISIBLE (-11125 3450);
FORCEPROP 2 LAST CDS_LOCATION R8A8
J 0
(-11125 3400);
DISPLAY 0.617021 (-11125 3400);
PAINT AQUA (-11125 3400);
DISPLAY INVISIBLE (-11125 3400);
FORCEPROP 1 LAST PATH I172
J 0
(-11125 3500);
DISPLAY 0.978723 (-11125 3500);
PAINT WHITE (-11125 3500);
DISPLAY INVISIBLE (-11125 3500);
FORCEPROP 2 LAST CDS_LIB mstr_discrete
J 0
(-11075 3350);
PAINT ORANGE (-11075 3350);
DISPLAY INVISIBLE (-11075 3350);
FORCEPROP 2 LAST $SEC 1
J 0
(-11125 3550);
PAINT MONO (-11125 3550);
DISPLAY INVISIBLE (-11125 3550);
FORCEPROP 2 LAST CDS_SEC 1
J 0
(-11125 3550);
PAINT MONO (-11125 3550);
DISPLAY INVISIBLE (-11125 3550);
FORCEADD RES..1
(-11400 3300);
FORCEPROP 1 LAST VALUE 20.0
J 2
(-11425 3200);
DISPLAY 0.617021 (-11425 3200);
PAINT SKYBLUE (-11425 3200);
FORCEPROP 1 LAST WATTAGE 1/16W
J 2
(-11425 3150);
DISPLAY 0.617021 (-11425 3150);
PAINT SKYBLUE (-11425 3150);
FORCEPROP 1 LAST MATERIAL CHIP
J 0
(-11400 3150);
DISPLAY 0.617021 (-11400 3150);
PAINT SKYBLUE (-11400 3150);
FORCEPROP 1 LAST TOLERANCE 1%
J 0
(-11400 3200);
DISPLAY 0.617021 (-11400 3200);
PAINT SKYBLUE (-11400 3200);
FORCEPROP 1 LAST LOCATION R8A9
J 0
(-11450 3350);
DISPLAY 0.617021 (-11450 3350);
PAINT AQUA (-11450 3350);
FORCEPROP 1 LAST PACK_TYPE 0402
J 0
(-11275 3150);
DISPLAY 0.617021 (-11275 3150);
PAINT SKYBLUE (-11275 3150);
FORCEPROP 1 LAST PART_NUMBER G21796-173
J 0
(-11450 3400);
DISPLAY 0.617021 (-11450 3400);
PAINT BLUE (-11450 3400);
FORCEPROP 2 LAST CDS_LIB mstr_discrete
J 0
(-11400 3300);
PAINT ORANGE (-11400 3300);
DISPLAY INVISIBLE (-11400 3300);
FORCEPROP 1 LASTPIN (-11300 3300) $PN 2
J 0
(-11338 3312);
DISPLAY 0.787234 (-11338 3312);
PAINT ORANGE (-11338 3312);
DISPLAY INVISIBLE (-11338 3312);
FORCEPROP 1 LASTPIN (-11500 3300) $PN 1
J 0
(-11488 3312);
DISPLAY 0.787234 (-11488 3312);
PAINT ORANGE (-11488 3312);
DISPLAY INVISIBLE (-11488 3312);
FORCEPROP 2 LAST CDS_SEC 1
J 0
(-11450 3500);
PAINT MONO (-11450 3500);
DISPLAY INVISIBLE (-11450 3500);
FORCEPROP 2 LAST $SEC 1
J 0
(-11450 3500);
PAINT MONO (-11450 3500);
DISPLAY INVISIBLE (-11450 3500);
FORCEPROP 2 LAST CDS_LOCATION R8A9
J 0
(-11450 3350);
DISPLAY 0.617021 (-11450 3350);
PAINT AQUA (-11450 3350);
DISPLAY INVISIBLE (-11450 3350);
FORCEPROP 2 LAST ROOM PVNN_PCH_STBY
J 0
(-11450 3400);
DISPLAY 1.361702 (-11450 3400);
PAINT ORANGE (-11450 3400);
DISPLAY INVISIBLE (-11450 3400);
FORCEPROP 1 LAST PATH I173
J 0
(-11450 3450);
DISPLAY 0.978723 (-11450 3450);
PAINT WHITE (-11450 3450);
DISPLAY INVISIBLE (-11450 3450);
FORCEADD RES..2
(-10750 2250);
FORCEPROP 1 LASTPIN (-10750 2150) $PN 2
J 0
(-10745 2160);
DISPLAY 0.617021 (-10745 2160);
PAINT ORANGE (-10745 2160);
FORCEPROP 1 LAST WATTAGE 1/16W
J 0
(-10710 2225);
DISPLAY 0.617021 (-10710 2225);
PAINT SKYBLUE (-10710 2225);
FORCEPROP 1 LAST MATERIAL CHIP
J 0
(-10710 2175);
DISPLAY 0.617021 (-10710 2175);
PAINT SKYBLUE (-10710 2175);
FORCEPROP 1 LAST PACK_TYPE 0402
J 0
(-10710 2075);
DISPLAY 0.617021 (-10710 2075);
PAINT SKYBLUE (-10710 2075);
FORCEPROP 1 LAST TOLERANCE 1%
J 0
(-10705 2275);
DISPLAY 0.617021 (-10705 2275);
PAINT SKYBLUE (-10705 2275);
FORCEPROP 1 LAST LOCATION R2L9
J 0
(-10705 2375);
DISPLAY 0.617021 (-10705 2375);
PAINT AQUA (-10705 2375);
FORCEPROP 1 LAST VALUE 4.02K
J 0
(-10705 2325);
DISPLAY 0.617021 (-10705 2325);
PAINT SKYBLUE (-10705 2325);
FORCEPROP 1 LASTPIN (-10750 2350) $PN 1
J 0
(-10745 2312);
DISPLAY 0.617021 (-10745 2312);
PAINT ORANGE (-10745 2312);
FORCEPROP 1 LAST PART_NUMBER G21796-082
J 0
(-10710 2125);
DISPLAY 0.617021 (-10710 2125);
PAINT BLUE (-10710 2125);
FORCEPROP 2 LAST CDS_LIB mstr_discrete
J 0
(-10750 2250);
PAINT ORANGE (-10750 2250);
DISPLAY INVISIBLE (-10750 2250);
FORCEPROP 2 LAST SEC_TYPE 0402
J 0
(-10700 2475);
DISPLAY 1.021277 (-10700 2475);
PAINT ORANGE (-10700 2475);
DISPLAY INVISIBLE (-10700 2475);
FORCEPROP 0 LAST SEC 1
J 0
(-10700 2425);
DISPLAY 0.680851 (-10700 2425);
PAINT MONO (-10700 2425);
DISPLAY INVISIBLE (-10700 2425);
FORCEPROP 2 LAST CDS_LOCATION R2L9
J 0
(-10705 2375);
DISPLAY 0.617021 (-10705 2375);
PAINT AQUA (-10705 2375);
DISPLAY INVISIBLE (-10705 2375);
FORCEPROP 1 LAST PATH I176
J 0
(-10700 2425);
DISPLAY 0.978723 (-10700 2425);
PAINT WHITE (-10700 2425);
DISPLAY INVISIBLE (-10700 2425);
FORCEPROP 2 LAST ROOM PVNN_PCH_STBY
J 0
(-10700 2475);
DISPLAY 1.021277 (-10700 2475);
PAINT ORANGE (-10700 2475);
DISPLAY INVISIBLE (-10700 2475);
FORCEADD GND..1
(-10750 1675);
FORCEPROP 3 LASTPIN (-10750 1725) SIG_NAME GND\g
J 0
(-10740 1735);
DISPLAY 0.659574 (-10740 1735);
PAINT MONO (-10740 1735);
DISPLAY INVISIBLE (-10740 1735);
FORCEPROP 2 LAST ROOM PVNN_PCH_STBY
J 0
(-11325 1750);
DISPLAY 1.361702 (-11325 1750);
PAINT ORANGE (-11325 1750);
DISPLAY INVISIBLE (-11325 1750);
FORCEPROP 1 LAST BODY_TYPE PLUMBING
J 0
(-10795 1632);
DISPLAY 0.340426 (-10795 1632);
PAINT GREEN (-10795 1632);
DISPLAY INVISIBLE (-10795 1632);
FORCEPROP 2 LAST CDS_LIB mstr_symbols
J 0
(-10750 1675);
PAINT ORANGE (-10750 1675);
DISPLAY INVISIBLE (-10750 1675);
FORCEPROP 1 LAST SIZE 1B
J 0
(-10675 1625);
DISPLAY 1.170213 (-10675 1625);
PAINT AQUA (-10675 1625);
DISPLAY INVISIBLE (-10675 1625);
FORCEPROP 1 LAST PATH I178
J 0
(-10675 1675);
DISPLAY 0.872340 (-10675 1675);
PAINT AQUA (-10675 1675);
DISPLAY INVISIBLE (-10675 1675);
FORCEPROP 1 LAST VOLTAGE 0
J 0
(-10750 1675);
PAINT SKYBLUE (-10750 1675);
DISPLAY INVISIBLE (-10750 1675);
FORCEPROP 1 LAST HDL_POWER GND
J 0
(-10750 1825);
DISPLAY 1.170213 (-10750 1825);
PAINT GREEN (-10750 1825);
DISPLAY INVISIBLE (-10750 1825);
FORCEADD GND..1
(-12325 4925);
FORCEPROP 3 LASTPIN (-12325 4975) SIG_NAME GND\g
J 0
(-12315 4985);
DISPLAY 0.659574 (-12315 4985);
PAINT MONO (-12315 4985);
DISPLAY INVISIBLE (-12315 4985);
FORCEPROP 2 LAST ROOM PVNN_PCH_STBY
J 0
(-12900 5000);
DISPLAY 1.361702 (-12900 5000);
PAINT ORANGE (-12900 5000);
DISPLAY INVISIBLE (-12900 5000);
FORCEPROP 1 LAST VOLTAGE 0
J 0
(-12325 4925);
PAINT SKYBLUE (-12325 4925);
DISPLAY INVISIBLE (-12325 4925);
FORCEPROP 2 LAST CDS_LIB mstr_symbols
J 0
(-12325 4925);
PAINT ORANGE (-12325 4925);
DISPLAY INVISIBLE (-12325 4925);
FORCEPROP 1 LAST BODY_TYPE PLUMBING
J 0
(-12370 4882);
DISPLAY 0.340426 (-12370 4882);
PAINT GREEN (-12370 4882);
DISPLAY INVISIBLE (-12370 4882);
FORCEPROP 1 LAST HDL_POWER GND
J 0
(-12325 5075);
DISPLAY 1.170213 (-12325 5075);
PAINT GREEN (-12325 5075);
DISPLAY INVISIBLE (-12325 5075);
FORCEPROP 1 LAST PATH I181
J 0
(-12250 4925);
DISPLAY 0.872340 (-12250 4925);
PAINT AQUA (-12250 4925);
DISPLAY INVISIBLE (-12250 4925);
FORCEPROP 1 LAST SIZE 1B
J 0
(-12250 4875);
DISPLAY 1.170213 (-12250 4875);
PAINT AQUA (-12250 4875);
DISPLAY INVISIBLE (-12250 4875);
FORCEADD GND..1
(-12550 4925);
FORCEPROP 3 LASTPIN (-12550 4975) SIG_NAME GND\g
J 0
(-12540 4985);
DISPLAY 0.659574 (-12540 4985);
PAINT MONO (-12540 4985);
DISPLAY INVISIBLE (-12540 4985);
FORCEPROP 2 LAST ROOM PVNN_PCH_STBY
J 0
(-13125 5000);
DISPLAY 1.361702 (-13125 5000);
PAINT ORANGE (-13125 5000);
DISPLAY INVISIBLE (-13125 5000);
FORCEPROP 1 LAST BODY_TYPE PLUMBING
J 0
(-12595 4882);
DISPLAY 0.340426 (-12595 4882);
PAINT GREEN (-12595 4882);
DISPLAY INVISIBLE (-12595 4882);
FORCEPROP 2 LAST CDS_LIB mstr_symbols
J 0
(-12550 4925);
PAINT ORANGE (-12550 4925);
DISPLAY INVISIBLE (-12550 4925);
FORCEPROP 1 LAST VOLTAGE 0
J 0
(-12550 4925);
PAINT SKYBLUE (-12550 4925);
DISPLAY INVISIBLE (-12550 4925);
FORCEPROP 1 LAST SIZE 1B
J 0
(-12475 4875);
DISPLAY 1.170213 (-12475 4875);
PAINT AQUA (-12475 4875);
DISPLAY INVISIBLE (-12475 4875);
FORCEPROP 1 LAST PATH I183
J 0
(-12475 4925);
DISPLAY 0.872340 (-12475 4925);
PAINT AQUA (-12475 4925);
DISPLAY INVISIBLE (-12475 4925);
FORCEPROP 1 LAST HDL_POWER GND
J 0
(-12550 5075);
DISPLAY 1.170213 (-12550 5075);
PAINT GREEN (-12550 5075);
DISPLAY INVISIBLE (-12550 5075);
FORCEADD OFFPAGE..1
(-12575 4300);
FORCEPROP 2 LAST $XR0 236 
J 0
(-12827 4300);
DISPLAY 0.638298 (-12827 4300);
PAINT MONO (-12827 4300);
FORCEPROP 2 LAST ROOM PVNN_PCH_STBY
J 0
(-13125 4375);
DISPLAY 1.361702 (-13125 4375);
PAINT ORANGE (-13125 4375);
DISPLAY INVISIBLE (-13125 4375);
FORCEPROP 2 LAST PATH I185
J 0
(-12825 4350);
DISPLAY 1.021277 (-12825 4350);
PAINT ORANGE (-12825 4350);
DISPLAY INVISIBLE (-12825 4350);
FORCEPROP 2 LAST CDS_LIB mstr_standard
J 0
(-12575 4300);
PAINT ORANGE (-12575 4300);
DISPLAY INVISIBLE (-12575 4300);
FORCEPROP 1 LAST COMMENT_BODY TRUE
J 0
(-12450 4200);
DISPLAY 1.170213 (-12450 4200);
PAINT GREEN (-12450 4200);
DISPLAY INVISIBLE (-12450 4200);
FORCEPROP 1 LAST OFFPAGE TRUE
J 0
(-12250 4175);
DISPLAY 1.170213 (-12250 4175);
PAINT GREEN (-12250 4175);
DISPLAY INVISIBLE (-12250 4175);
FORCEADD OFFPAGE..1
(-12850 4350);
FORCEPROP 2 LAST $XR0 236 
J 0
(-13132 4350);
DISPLAY 0.638298 (-13132 4350);
PAINT MONO (-13132 4350);
FORCEPROP 2 LAST ROOM PVNN_PCH_STBY
J 0
(-13400 4425);
DISPLAY 1.361702 (-13400 4425);
PAINT ORANGE (-13400 4425);
DISPLAY INVISIBLE (-13400 4425);
FORCEPROP 2 LAST PATH I186
J 0
(-13100 4400);
DISPLAY 1.021277 (-13100 4400);
PAINT ORANGE (-13100 4400);
DISPLAY INVISIBLE (-13100 4400);
FORCEPROP 2 LAST CDS_LIB mstr_standard
J 0
(-12850 4350);
PAINT ORANGE (-12850 4350);
DISPLAY INVISIBLE (-12850 4350);
FORCEPROP 1 LAST COMMENT_BODY TRUE
J 0
(-12725 4250);
DISPLAY 1.170213 (-12725 4250);
PAINT GREEN (-12725 4250);
DISPLAY INVISIBLE (-12725 4250);
FORCEPROP 1 LAST OFFPAGE TRUE
J 0
(-12525 4225);
DISPLAY 1.170213 (-12525 4225);
PAINT GREEN (-12525 4225);
DISPLAY INVISIBLE (-12525 4225);
FORCEADD OFFPAGE..1
(-12575 4150);
FORCEPROP 2 LAST $XR0 237 
J 0
(-12827 4150);
DISPLAY 0.638298 (-12827 4150);
PAINT MONO (-12827 4150);
FORCEPROP 1 LAST COMMENT_BODY TRUE
J 0
(-12450 4050);
DISPLAY 1.170213 (-12450 4050);
PAINT GREEN (-12450 4050);
DISPLAY INVISIBLE (-12450 4050);
FORCEPROP 2 LAST ROOM PVNN_PCH_STBY
J 0
(-13125 4225);
DISPLAY 1.361702 (-13125 4225);
PAINT ORANGE (-13125 4225);
DISPLAY INVISIBLE (-13125 4225);
FORCEPROP 2 LAST CDS_LIB mstr_standard
J 0
(-12575 4150);
PAINT ORANGE (-12575 4150);
DISPLAY INVISIBLE (-12575 4150);
FORCEPROP 2 LAST PATH I187
J 0
(-12525 4225);
DISPLAY 1.021277 (-12525 4225);
PAINT ORANGE (-12525 4225);
DISPLAY INVISIBLE (-12525 4225);
FORCEPROP 1 LAST OFFPAGE TRUE
J 0
(-12250 4025);
DISPLAY 1.170213 (-12250 4025);
PAINT GREEN (-12250 4025);
DISPLAY INVISIBLE (-12250 4025);
FORCEADD OFFPAGE..1
(-12575 4200);
FORCEPROP 2 LAST $XR0 236 
J 0
(-12827 4200);
DISPLAY 0.638298 (-12827 4200);
PAINT MONO (-12827 4200);
FORCEPROP 2 LAST ROOM PVNN_PCH_STBY
J 0
(-13125 4275);
DISPLAY 1.361702 (-13125 4275);
PAINT ORANGE (-13125 4275);
DISPLAY INVISIBLE (-13125 4275);
FORCEPROP 2 LAST PATH I188
J 0
(-12825 4250);
DISPLAY 1.021277 (-12825 4250);
PAINT ORANGE (-12825 4250);
DISPLAY INVISIBLE (-12825 4250);
FORCEPROP 2 LAST CDS_LIB mstr_standard
J 0
(-12575 4200);
PAINT ORANGE (-12575 4200);
DISPLAY INVISIBLE (-12575 4200);
FORCEPROP 1 LAST COMMENT_BODY TRUE
J 0
(-12450 4100);
DISPLAY 1.170213 (-12450 4100);
PAINT GREEN (-12450 4100);
DISPLAY INVISIBLE (-12450 4100);
FORCEPROP 1 LAST OFFPAGE TRUE
J 0
(-12250 4075);
DISPLAY 1.170213 (-12250 4075);
PAINT GREEN (-12250 4075);
DISPLAY INVISIBLE (-12250 4075);
FORCEADD OFFPAGE..1
(-12575 4050);
FORCEPROP 2 LAST $XR0 235 
J 0
(-12827 4050);
DISPLAY 0.638298 (-12827 4050);
PAINT MONO (-12827 4050);
FORCEPROP 2 LAST CDS_LIB mstr_standard
J 0
(-12575 4050);
PAINT ORANGE (-12575 4050);
DISPLAY INVISIBLE (-12575 4050);
FORCEPROP 1 LAST COMMENT_BODY TRUE
J 0
(-12450 3950);
DISPLAY 1.170213 (-12450 3950);
PAINT GREEN (-12450 3950);
DISPLAY INVISIBLE (-12450 3950);
FORCEPROP 2 LAST ROOM PVNN_PCH_STBY
J 0
(-13125 4125);
DISPLAY 1.361702 (-13125 4125);
PAINT ORANGE (-13125 4125);
DISPLAY INVISIBLE (-13125 4125);
FORCEPROP 2 LAST PATH I189
J 0
(-12825 4100);
DISPLAY 1.021277 (-12825 4100);
PAINT ORANGE (-12825 4100);
DISPLAY INVISIBLE (-12825 4100);
FORCEPROP 1 LAST OFFPAGE TRUE
J 0
(-12250 3925);
DISPLAY 1.170213 (-12250 3925);
PAINT GREEN (-12250 3925);
DISPLAY INVISIBLE (-12250 3925);
FORCEADD OFFPAGE..2
R 2
(-12575 3900);
FORCEPROP 2 LAST $XR0 235 
J 0
(-12860 3900);
DISPLAY 0.638298 (-12860 3900);
PAINT MONO (-12860 3900);
FORCEPROP 2 LAST PATH I191
J 0
(-12850 3950);
DISPLAY 1.021277 (-12850 3950);
PAINT ORANGE (-12850 3950);
DISPLAY INVISIBLE (-12850 3950);
FORCEPROP 1 LAST OFFPAGE TRUE
J 2
(-12900 3775);
DISPLAY 1.170213 (-12900 3775);
PAINT GREEN (-12900 3775);
DISPLAY INVISIBLE (-12900 3775);
FORCEPROP 2 LAST ROOM PVNN_PCH_STBY
J 0
(-13125 3975);
DISPLAY 1.361702 (-13125 3975);
PAINT ORANGE (-13125 3975);
DISPLAY INVISIBLE (-13125 3975);
FORCEPROP 2 LAST CDS_LIB mstr_standard
J 0
(-12575 3900);
PAINT ORANGE (-12575 3900);
DISPLAY INVISIBLE (-12575 3900);
FORCEPROP 1 LAST COMMENT_BODY TRUE
J 2
(-12530 3805);
DISPLAY 1.170213 (-12530 3805);
PAINT GREEN (-12530 3805);
DISPLAY INVISIBLE (-12530 3805);
FORCEADD OFFPAGE..2
R 2
(-12575 3300);
FORCEPROP 2 LAST $XR0 138 
J 0
(-12860 3300);
DISPLAY 0.638298 (-12860 3300);
PAINT MONO (-12860 3300);
FORCEPROP 2 LAST $XR1 159 
J 0
(-12980 3300);
DISPLAY 0.638298 (-12980 3300);
PAINT MONO (-12980 3300);
FORCEPROP 2 LAST $XR2 211 
J 0
(-13100 3300);
DISPLAY 0.638298 (-13100 3300);
PAINT MONO (-13100 3300);
FORCEPROP 2 LAST $XR3 213 
J 0
(-13220 3300);
DISPLAY 0.638298 (-13220 3300);
PAINT MONO (-13220 3300);
FORCEPROP 2 LAST $XR4 193 
J 0
(-13340 3300);
DISPLAY 0.638298 (-13340 3300);
PAINT MONO (-13340 3300);
FORCEPROP 2 LAST $XR5 194 
J 0
(-13460 3300);
DISPLAY 0.638298 (-13460 3300);
PAINT MONO (-13460 3300);
FORCEPROP 2 LAST $XR6 201 
J 0
(-13580 3300);
DISPLAY 0.638298 (-13580 3300);
PAINT MONO (-13580 3300);
FORCEPROP 2 LAST $XR7 206 
J 0
(-13700 3300);
DISPLAY 0.638298 (-13700 3300);
PAINT MONO (-13700 3300);
FORCEPROP 2 LAST $XR8 215 
J 0
(-12860 3264);
DISPLAY 0.638298 (-12860 3264);
PAINT MONO (-12860 3264);
FORCEPROP 2 LAST $XR9 218 
J 0
(-12980 3264);
DISPLAY 0.638298 (-12980 3264);
PAINT MONO (-12980 3264);
FORCEPROP 2 LAST $XR10 223 
J 0
(-13100 3264);
DISPLAY 0.638298 (-13100 3264);
PAINT MONO (-13100 3264);
FORCEPROP 2 LAST $XR11 226 
J 0
(-13220 3264);
DISPLAY 0.638298 (-13220 3264);
PAINT MONO (-13220 3264);
FORCEPROP 2 LAST ROOM PVNN_PCH_STBY
J 0
(-13125 3375);
DISPLAY 1.361702 (-13125 3375);
PAINT ORANGE (-13125 3375);
DISPLAY INVISIBLE (-13125 3375);
FORCEPROP 1 LAST OFFPAGE TRUE
J 2
(-12900 3175);
DISPLAY 1.170213 (-12900 3175);
PAINT GREEN (-12900 3175);
DISPLAY INVISIBLE (-12900 3175);
FORCEPROP 2 LAST PATH I194
J 0
(-12850 3350);
DISPLAY 1.021277 (-12850 3350);
PAINT ORANGE (-12850 3350);
DISPLAY INVISIBLE (-12850 3350);
FORCEPROP 2 LAST CDS_LIB mstr_standard
J 0
(-12575 3300);
PAINT ORANGE (-12575 3300);
DISPLAY INVISIBLE (-12575 3300);
FORCEPROP 1 LAST COMMENT_BODY TRUE
J 2
(-12530 3205);
DISPLAY 1.170213 (-12530 3205);
PAINT GREEN (-12530 3205);
DISPLAY INVISIBLE (-12530 3205);
FORCEADD OFFPAGE..3
R 2
(-12575 3350);
FORCEPROP 2 LAST $XR0 138 
J 0
(-12885 3350);
DISPLAY 0.638298 (-12885 3350);
PAINT MONO (-12885 3350);
FORCEPROP 2 LAST $XR1 159 
J 0
(-13005 3350);
DISPLAY 0.638298 (-13005 3350);
PAINT MONO (-13005 3350);
FORCEPROP 2 LAST $XR2 193 
J 0
(-13125 3350);
DISPLAY 0.638298 (-13125 3350);
PAINT MONO (-13125 3350);
FORCEPROP 2 LAST $XR3 194 
J 0
(-13245 3350);
DISPLAY 0.638298 (-13245 3350);
PAINT MONO (-13245 3350);
FORCEPROP 2 LAST $XR4 201 
J 0
(-13365 3350);
DISPLAY 0.638298 (-13365 3350);
PAINT MONO (-13365 3350);
FORCEPROP 2 LAST $XR5 206 
J 0
(-13485 3350);
DISPLAY 0.638298 (-13485 3350);
PAINT MONO (-13485 3350);
FORCEPROP 2 LAST $XR6 211 
J 0
(-13605 3350);
DISPLAY 0.638298 (-13605 3350);
PAINT MONO (-13605 3350);
FORCEPROP 2 LAST $XR7 213 
J 0
(-13725 3350);
DISPLAY 0.638298 (-13725 3350);
PAINT MONO (-13725 3350);
FORCEPROP 2 LAST $XR8 215 
J 0
(-12885 3386);
DISPLAY 0.638298 (-12885 3386);
PAINT MONO (-12885 3386);
FORCEPROP 2 LAST $XR9 218 
J 0
(-13005 3386);
DISPLAY 0.638298 (-13005 3386);
PAINT MONO (-13005 3386);
FORCEPROP 2 LAST $XR10 223 
J 0
(-13125 3386);
DISPLAY 0.638298 (-13125 3386);
PAINT MONO (-13125 3386);
FORCEPROP 2 LAST $XR11 226 
J 0
(-13245 3386);
DISPLAY 0.638298 (-13245 3386);
PAINT MONO (-13245 3386);
FORCEPROP 2 LAST ROOM PVNN_PCH_STBY
J 0
(-13125 3425);
DISPLAY 1.361702 (-13125 3425);
PAINT ORANGE (-13125 3425);
DISPLAY INVISIBLE (-13125 3425);
FORCEPROP 1 LAST OFFPAGE TRUE
J 2
(-12900 3225);
DISPLAY 0.872340 (-12900 3225);
PAINT GREEN (-12900 3225);
DISPLAY INVISIBLE (-12900 3225);
FORCEPROP 2 LAST PATH I195
J 0
(-12850 3425);
DISPLAY 1.021277 (-12850 3425);
PAINT ORANGE (-12850 3425);
DISPLAY INVISIBLE (-12850 3425);
FORCEPROP 2 LAST CDS_LIB mstr_standard
J 0
(-12575 3350);
PAINT ORANGE (-12575 3350);
DISPLAY INVISIBLE (-12575 3350);
FORCEPROP 1 LAST COMMENT_BODY TRUE
J 2
(-12525 3250);
DISPLAY 0.872340 (-12525 3250);
PAINT GREEN (-12525 3250);
DISPLAY INVISIBLE (-12525 3250);
FORCEADD OFFPAGE..2
(-7125 3950);
FORCEPROP 2 LAST $XR0 236 
J 0
(-6936 3950);
DISPLAY 0.638298 (-6936 3950);
PAINT MONO (-6936 3950);
FORCEPROP 2 LAST ROOM PVNN_PCH_STBY
J 0
(-7550 4025);
DISPLAY 1.361702 (-7550 4025);
PAINT ORANGE (-7550 4025);
DISPLAY INVISIBLE (-7550 4025);
FORCEPROP 1 LAST COMMENT_BODY TRUE
J 0
(-7170 3855);
DISPLAY 1.170213 (-7170 3855);
PAINT GREEN (-7170 3855);
DISPLAY INVISIBLE (-7170 3855);
FORCEPROP 2 LAST CDS_LIB mstr_standard
J 0
(-7125 3950);
PAINT ORANGE (-7125 3950);
DISPLAY INVISIBLE (-7125 3950);
FORCEPROP 2 LAST PATH I198
J 0
(-6950 4025);
DISPLAY 1.021277 (-6950 4025);
PAINT ORANGE (-6950 4025);
DISPLAY INVISIBLE (-6950 4025);
FORCEPROP 1 LAST OFFPAGE TRUE
J 0
(-6800 3825);
DISPLAY 1.170213 (-6800 3825);
PAINT GREEN (-6800 3825);
DISPLAY INVISIBLE (-6800 3825);
FORCEADD OFFPAGE..1
(-12575 3100);
FORCEPROP 2 LAST $XR0 236 
J 0
(-12827 3100);
DISPLAY 0.638298 (-12827 3100);
PAINT MONO (-12827 3100);
FORCEPROP 1 LAST COMMENT_BODY TRUE
J 0
(-12450 3000);
DISPLAY 1.170213 (-12450 3000);
PAINT GREEN (-12450 3000);
DISPLAY INVISIBLE (-12450 3000);
FORCEPROP 2 LAST ROOM PVNN_PCH_STBY
J 0
(-13125 3175);
DISPLAY 1.361702 (-13125 3175);
PAINT ORANGE (-13125 3175);
DISPLAY INVISIBLE (-13125 3175);
FORCEPROP 2 LAST CDS_LIB mstr_standard
J 0
(-12575 3100);
PAINT ORANGE (-12575 3100);
DISPLAY INVISIBLE (-12575 3100);
FORCEPROP 2 LAST PATH I199
J 0
(-12525 3175);
DISPLAY 1.021277 (-12525 3175);
PAINT ORANGE (-12525 3175);
DISPLAY INVISIBLE (-12525 3175);
FORCEPROP 1 LAST OFFPAGE TRUE
J 0
(-12250 2975);
DISPLAY 1.170213 (-12250 2975);
PAINT GREEN (-12250 2975);
DISPLAY INVISIBLE (-12250 2975);
FORCEADD OFFPAGE..1
(-12575 3050);
FORCEPROP 2 LAST $XR0 236 
J 0
(-12887 3050);
DISPLAY 0.638298 (-12887 3050);
PAINT MONO (-12887 3050);
FORCEPROP 1 LAST COMMENT_BODY TRUE
J 0
(-12450 2950);
DISPLAY 1.170213 (-12450 2950);
PAINT GREEN (-12450 2950);
DISPLAY INVISIBLE (-12450 2950);
FORCEPROP 2 LAST CDS_LIB mstr_standard
J 0
(-12575 3050);
PAINT ORANGE (-12575 3050);
DISPLAY INVISIBLE (-12575 3050);
FORCEPROP 2 LAST ROOM PVNN_PCH_STBY
J 0
(-13125 3125);
DISPLAY 1.361702 (-13125 3125);
PAINT ORANGE (-13125 3125);
DISPLAY INVISIBLE (-13125 3125);
FORCEPROP 2 LAST PATH I200
J 0
(-12525 3125);
DISPLAY 1.021277 (-12525 3125);
PAINT ORANGE (-12525 3125);
DISPLAY INVISIBLE (-12525 3125);
FORCEPROP 1 LAST OFFPAGE TRUE
J 0
(-12250 2925);
DISPLAY 1.170213 (-12250 2925);
PAINT GREEN (-12250 2925);
DISPLAY INVISIBLE (-12250 2925);
FORCEADD CAP..1
(-12375 2600);
FORCEPROP 1 LASTPIN (-12375 2500) $PN 2
J 0
(-12365 2480);
DISPLAY 0.617021 (-12365 2480);
PAINT ORANGE (-12365 2480);
FORCEPROP 1 LASTPIN (-12375 2700) $PN 1
J 0
(-12365 2680);
DISPLAY 0.617021 (-12365 2680);
PAINT ORANGE (-12365 2680);
FORCEPROP 2 LAST NO_XNET_CONNECTION 1
J 0
(-12325 2800);
PAINT MONO (-12325 2800);
FORCEPROP 1 LAST VOLTAGE 50V
J 0
(-12325 2600);
DISPLAY 0.617021 (-12325 2600);
PAINT SKYBLUE (-12325 2600);
FORCEPROP 1 LAST PACK_TYPE 0402LF
J 0
(-12325 2500);
DISPLAY 0.617021 (-12325 2500);
PAINT SKYBLUE (-12325 2500);
FORCEPROP 1 LAST VALUE 220PF
J 0
(-12325 2650);
DISPLAY 0.617021 (-12325 2650);
PAINT SKYBLUE (-12325 2650);
FORCEPROP 1 LAST PART_NUMBER A36096-050
J 0
(-12325 2550);
DISPLAY 0.617021 (-12325 2550);
PAINT BLUE (-12325 2550);
FORCEPROP 1 LAST LOCATION C8A2
J 0
(-12325 2700);
DISPLAY 0.617021 (-12325 2700);
PAINT AQUA (-12325 2700);
FORCEPROP 1 LAST MATERIAL X7R
J 0
(-12200 2600);
DISPLAY 0.617021 (-12200 2600);
PAINT SKYBLUE (-12200 2600);
FORCEPROP 1 LAST TOLERANCE 10%
J 0
(-12150 2650);
DISPLAY 0.617021 (-12150 2650);
PAINT SKYBLUE (-12150 2650);
FORCEPROP 2 LAST CDS_LIB mstr_discrete
J 0
(-12375 2600);
PAINT ORANGE (-12375 2600);
DISPLAY INVISIBLE (-12375 2600);
FORCEPROP 2 LAST CDS_LOCATION C8A2
J 0
(-12325 2700);
DISPLAY 0.617021 (-12325 2700);
PAINT AQUA (-12325 2700);
DISPLAY INVISIBLE (-12325 2700);
FORCEPROP 1 LAST PATH I209
J 0
(-12325 2750);
DISPLAY 0.978723 (-12325 2750);
PAINT WHITE (-12325 2750);
DISPLAY INVISIBLE (-12325 2750);
FORCEPROP 2 LAST ROOM PVNN_PCH_STBY
J 0
(-12325 2750);
DISPLAY 1.361702 (-12325 2750);
PAINT ORANGE (-12325 2750);
DISPLAY INVISIBLE (-12325 2750);
FORCEPROP 2 LAST SEC_TYPE 0402LF
J 0
(-12325 2825);
DISPLAY 1.021277 (-12325 2825);
PAINT ORANGE (-12325 2825);
DISPLAY INVISIBLE (-12325 2825);
FORCEPROP 2 LAST SEC 1
J 0
(-12325 2825);
DISPLAY 0.680851 (-12325 2825);
PAINT MONO (-12325 2825);
DISPLAY INVISIBLE (-12325 2825);
FORCEADD RES..1
(-12675 2750);
FORCEPROP 1 LAST WATTAGE 1/16W
J 2
(-12675 2600);
DISPLAY 0.617021 (-12675 2600);
PAINT SKYBLUE (-12675 2600);
FORCEPROP 1 LAST VALUE 10.0
J 2
(-12775 2650);
DISPLAY 0.617021 (-12775 2650);
PAINT SKYBLUE (-12775 2650);
FORCEPROP 1 LAST PART_NUMBER G21796-066
J 0
(-12825 2700);
DISPLAY 0.617021 (-12825 2700);
PAINT BLUE (-12825 2700);
FORCEPROP 1 LAST TOLERANCE 1%
J 0
(-12750 2650);
DISPLAY 0.617021 (-12750 2650);
PAINT SKYBLUE (-12750 2650);
FORCEPROP 1 LASTPIN (-12775 2750) $PN 1
J 0
(-12763 2762);
DISPLAY 0.617021 (-12763 2762);
PAINT ORANGE (-12763 2762);
FORCEPROP 1 LASTPIN (-12575 2750) $PN 2
J 0
(-12613 2762);
DISPLAY 0.617021 (-12613 2762);
PAINT ORANGE (-12613 2762);
FORCEPROP 1 LAST LOCATION R8A1
J 0
(-12725 2800);
DISPLAY 0.617021 (-12725 2800);
PAINT AQUA (-12725 2800);
FORCEPROP 2 LAST NO_XNET_CONNECTION 1
J 0
(-12725 2950);
PAINT MONO (-12725 2950);
FORCEPROP 1 LAST MATERIAL CHIP
J 0
(-12650 2600);
DISPLAY 0.617021 (-12650 2600);
PAINT SKYBLUE (-12650 2600);
FORCEPROP 1 LAST PACK_TYPE 0402
J 0
(-12650 2650);
DISPLAY 0.617021 (-12650 2650);
PAINT SKYBLUE (-12650 2650);
FORCEPROP 2 LAST CDS_LIB mstr_discrete
J 0
(-12675 2750);
PAINT ORANGE (-12675 2750);
DISPLAY INVISIBLE (-12675 2750);
FORCEPROP 2 LAST CDS_LOCATION R8A1
J 0
(-12725 2800);
DISPLAY 0.617021 (-12725 2800);
PAINT AQUA (-12725 2800);
DISPLAY INVISIBLE (-12725 2800);
FORCEPROP 1 LAST PATH I210
J 0
(-12725 2900);
DISPLAY 0.978723 (-12725 2900);
PAINT WHITE (-12725 2900);
DISPLAY INVISIBLE (-12725 2900);
FORCEPROP 2 LAST SEC 1
J 0
(-12725 2975);
DISPLAY 0.680851 (-12725 2975);
PAINT MONO (-12725 2975);
DISPLAY INVISIBLE (-12725 2975);
FORCEPROP 2 LAST SEC_TYPE 0402
J 0
(-12725 2975);
DISPLAY 1.021277 (-12725 2975);
PAINT ORANGE (-12725 2975);
DISPLAY INVISIBLE (-12725 2975);
FORCEPROP 2 LAST ROOM PVNN_PCH_STBY
J 0
(-12600 2850);
DISPLAY 1.361702 (-12600 2850);
PAINT ORANGE (-12600 2850);
DISPLAY INVISIBLE (-12600 2850);
FORCEADD OFFPAGE..1
(-13400 2750);
FORCEPROP 2 LAST $XR0 236 
J 0
(-13652 2750);
DISPLAY 0.638298 (-13652 2750);
PAINT MONO (-13652 2750);
FORCEPROP 2 LAST ROOM PVNN_PCH_STBY
J 0
(-13950 2825);
DISPLAY 1.361702 (-13950 2825);
PAINT ORANGE (-13950 2825);
DISPLAY INVISIBLE (-13950 2825);
FORCEPROP 2 LAST CDS_LIB mstr_standard
J 0
(-13400 2750);
PAINT ORANGE (-13400 2750);
DISPLAY INVISIBLE (-13400 2750);
FORCEPROP 2 LAST PATH I211
J 0
(-13350 2825);
DISPLAY 1.021277 (-13350 2825);
PAINT ORANGE (-13350 2825);
DISPLAY INVISIBLE (-13350 2825);
FORCEPROP 1 LAST COMMENT_BODY TRUE
J 0
(-13275 2650);
DISPLAY 1.170213 (-13275 2650);
PAINT GREEN (-13275 2650);
DISPLAY INVISIBLE (-13275 2650);
FORCEPROP 1 LAST OFFPAGE TRUE
J 0
(-13075 2625);
DISPLAY 1.170213 (-13075 2625);
PAINT GREEN (-13075 2625);
DISPLAY INVISIBLE (-13075 2625);
FORCEADD OFFPAGE..1
(-13325 2475);
FORCEPROP 2 LAST $XR0 236 
J 0
(-13577 2475);
DISPLAY 0.638298 (-13577 2475);
PAINT MONO (-13577 2475);
FORCEPROP 2 LAST ROOM PVNN_PCH_STBY
J 0
(-13875 2550);
DISPLAY 1.361702 (-13875 2550);
PAINT ORANGE (-13875 2550);
DISPLAY INVISIBLE (-13875 2550);
FORCEPROP 2 LAST CDS_LIB mstr_standard
J 0
(-13325 2475);
PAINT ORANGE (-13325 2475);
DISPLAY INVISIBLE (-13325 2475);
FORCEPROP 2 LAST PATH I212
J 0
(-13275 2550);
DISPLAY 1.021277 (-13275 2550);
PAINT ORANGE (-13275 2550);
DISPLAY INVISIBLE (-13275 2550);
FORCEPROP 1 LAST COMMENT_BODY TRUE
J 0
(-13200 2375);
DISPLAY 1.170213 (-13200 2375);
PAINT GREEN (-13200 2375);
DISPLAY INVISIBLE (-13200 2375);
FORCEPROP 1 LAST OFFPAGE TRUE
J 0
(-13000 2350);
DISPLAY 1.170213 (-13000 2350);
PAINT GREEN (-13000 2350);
DISPLAY INVISIBLE (-13000 2350);
FORCEADD OFFPAGE..1
(-13025 3200);
FORCEPROP 2 LAST $XR0 236 
J 0
(-13277 3200);
DISPLAY 0.638298 (-13277 3200);
PAINT MONO (-13277 3200);
FORCEPROP 2 LAST ROOM PVNN_PCH_STBY
J 0
(-13575 3275);
DISPLAY 1.361702 (-13575 3275);
PAINT ORANGE (-13575 3275);
DISPLAY INVISIBLE (-13575 3275);
FORCEPROP 2 LAST CDS_LIB mstr_standard
J 0
(-13025 3200);
PAINT ORANGE (-13025 3200);
DISPLAY INVISIBLE (-13025 3200);
FORCEPROP 2 LAST PATH I215
J 0
(-12975 3275);
DISPLAY 1.021277 (-12975 3275);
PAINT ORANGE (-12975 3275);
DISPLAY INVISIBLE (-12975 3275);
FORCEPROP 1 LAST COMMENT_BODY TRUE
J 0
(-12900 3100);
DISPLAY 1.170213 (-12900 3100);
PAINT GREEN (-12900 3100);
DISPLAY INVISIBLE (-12900 3100);
FORCEPROP 1 LAST OFFPAGE TRUE
J 0
(-12700 3075);
DISPLAY 1.170213 (-12700 3075);
PAINT GREEN (-12700 3075);
DISPLAY INVISIBLE (-12700 3075);
FORCEADD RES..2
(-8200 4875);
FORCEPROP 1 LAST WATTAGE 1/16W
J 0
(-8160 4850);
DISPLAY 0.617021 (-8160 4850);
PAINT SKYBLUE (-8160 4850);
FORCEPROP 1 LAST MATERIAL CHIP
J 0
(-8160 4800);
DISPLAY 0.617021 (-8160 4800);
PAINT SKYBLUE (-8160 4800);
FORCEPROP 1 LAST PACK_TYPE 0402
J 0
(-8160 4700);
DISPLAY 0.617021 (-8160 4700);
PAINT SKYBLUE (-8160 4700);
FORCEPROP 1 LAST TOLERANCE 1%
J 0
(-8155 4900);
DISPLAY 0.617021 (-8155 4900);
PAINT SKYBLUE (-8155 4900);
FORCEPROP 1 LAST VALUE 1.00K
J 0
(-8155 4950);
DISPLAY 0.617021 (-8155 4950);
PAINT SKYBLUE (-8155 4950);
FORCEPROP 1 LAST LOCATION R8A5
J 0
(-8155 5000);
DISPLAY 0.617021 (-8155 5000);
PAINT AQUA (-8155 5000);
FORCEPROP 1 LAST PART_NUMBER G21796-026
J 0
(-8160 4750);
DISPLAY 0.617021 (-8160 4750);
PAINT BLUE (-8160 4750);
FORCEPROP 1 LASTPIN (-8200 4775) $PN 2
J 0
(-8195 4785);
DISPLAY 0.787234 (-8195 4785);
PAINT ORANGE (-8195 4785);
DISPLAY INVISIBLE (-8195 4785);
FORCEPROP 2 LAST CDS_LIB mstr_discrete
J 0
(-8200 4875);
PAINT ORANGE (-8200 4875);
DISPLAY INVISIBLE (-8200 4875);
FORCEPROP 1 LASTPIN (-8200 4975) $PN 1
J 0
(-8195 4937);
DISPLAY 0.787234 (-8195 4937);
PAINT ORANGE (-8195 4937);
DISPLAY INVISIBLE (-8195 4937);
FORCEPROP 1 LAST PATH I216
J 0
(-8150 5050);
DISPLAY 0.978723 (-8150 5050);
PAINT WHITE (-8150 5050);
DISPLAY INVISIBLE (-8150 5050);
FORCEPROP 2 LAST CDS_LOCATION R8A5
J 0
(-8155 5000);
DISPLAY 0.617021 (-8155 5000);
PAINT AQUA (-8155 5000);
DISPLAY INVISIBLE (-8155 5000);
FORCEPROP 2 LAST $SEC 1
J 0
(-8150 5100);
DISPLAY 0.680851 (-8150 5100);
PAINT MONO (-8150 5100);
DISPLAY INVISIBLE (-8150 5100);
FORCEPROP 2 LAST CDS_SEC 1
J 0
(-8150 5100);
DISPLAY 1.021277 (-8150 5100);
PAINT ORANGE (-8150 5100);
DISPLAY INVISIBLE (-8150 5100);
FORCEADD RES..2
(-10375 2275);
FORCEPROP 1 LAST TOLERANCE 1%
J 0
(-10330 2300);
DISPLAY 0.617021 (-10330 2300);
PAINT SKYBLUE (-10330 2300);
FORCEPROP 1 LAST WATTAGE 1/16W
J 0
(-10335 2250);
DISPLAY 0.617021 (-10335 2250);
PAINT SKYBLUE (-10335 2250);
FORCEPROP 1 LAST MATERIAL CHIP
J 0
(-10335 2200);
DISPLAY 0.617021 (-10335 2200);
PAINT SKYBLUE (-10335 2200);
FORCEPROP 1 LAST PACK_TYPE 0402
J 0
(-10335 2100);
DISPLAY 0.617021 (-10335 2100);
PAINT SKYBLUE (-10335 2100);
FORCEPROP 1 LAST VALUE 2.67K
J 0
(-10330 2350);
DISPLAY 0.617021 (-10330 2350);
PAINT SKYBLUE (-10330 2350);
FORCEPROP 1 LAST PART_NUMBER G21796-180
J 0
(-10335 2150);
DISPLAY 0.617021 (-10335 2150);
PAINT BLUE (-10335 2150);
FORCEPROP 1 LAST LOCATION R8A2
J 0
(-10330 2400);
DISPLAY 0.617021 (-10330 2400);
PAINT AQUA (-10330 2400);
FORCEPROP 1 LASTPIN (-10375 2175) $PN 2
J 0
(-10370 2185);
DISPLAY 0.787234 (-10370 2185);
PAINT ORANGE (-10370 2185);
DISPLAY INVISIBLE (-10370 2185);
FORCEPROP 2 LAST CDS_LIB mstr_discrete
J 0
(-10375 2275);
PAINT ORANGE (-10375 2275);
DISPLAY INVISIBLE (-10375 2275);
FORCEPROP 2 LAST $SEC 1
J 0
(-10325 2500);
DISPLAY 0.680851 (-10325 2500);
PAINT MONO (-10325 2500);
DISPLAY INVISIBLE (-10325 2500);
FORCEPROP 2 LAST CDS_LOCATION R8A2
J 0
(-10330 2400);
DISPLAY 0.617021 (-10330 2400);
PAINT AQUA (-10330 2400);
DISPLAY INVISIBLE (-10330 2400);
FORCEPROP 2 LAST CDS_SEC 1
J 0
(-10325 2500);
DISPLAY 1.021277 (-10325 2500);
PAINT ORANGE (-10325 2500);
DISPLAY INVISIBLE (-10325 2500);
FORCEPROP 1 LAST PATH I217
J 0
(-10325 2450);
DISPLAY 0.978723 (-10325 2450);
PAINT WHITE (-10325 2450);
DISPLAY INVISIBLE (-10325 2450);
FORCEPROP 1 LASTPIN (-10375 2375) $PN 1
J 0
(-10370 2337);
DISPLAY 0.787234 (-10370 2337);
PAINT ORANGE (-10370 2337);
DISPLAY INVISIBLE (-10370 2337);
FORCEADD CAP..1
(-8000 4325);
FORCEPROP 1 LASTPIN (-8000 4225) $PN 2
J 0
(-7990 4205);
DISPLAY 0.617021 (-7990 4205);
PAINT ORANGE (-7990 4205);
FORCEPROP 1 LASTPIN (-8000 4425) $PN 1
J 0
(-7990 4405);
DISPLAY 0.617021 (-7990 4405);
PAINT ORANGE (-7990 4405);
FORCEPROP 1 LAST MATERIAL X7R
J 0
(-7950 4225);
DISPLAY 0.617021 (-7950 4225);
PAINT SKYBLUE (-7950 4225);
FORCEPROP 1 LAST LOCATION C8A9
J 0
(-7950 4425);
DISPLAY 0.617021 (-7950 4425);
PAINT AQUA (-7950 4425);
FORCEPROP 1 LAST VALUE 1000PF
J 0
(-7950 4375);
DISPLAY 0.617021 (-7950 4375);
PAINT SKYBLUE (-7950 4375);
FORCEPROP 1 LAST VOLTAGE 50V
J 0
(-7950 4325);
DISPLAY 0.617021 (-7950 4325);
PAINT SKYBLUE (-7950 4325);
FORCEPROP 1 LAST PACK_TYPE 0402LF
J 0
(-7950 4125);
DISPLAY 0.617021 (-7950 4125);
PAINT SKYBLUE (-7950 4125);
FORCEPROP 1 LAST TOLERANCE 10%
J 0
(-7950 4275);
DISPLAY 0.617021 (-7950 4275);
PAINT SKYBLUE (-7950 4275);
FORCEPROP 1 LAST PART_NUMBER A36096-046
J 0
(-7950 4175);
DISPLAY 0.617021 (-7950 4175);
PAINT BLUE (-7950 4175);
FORCEPROP 2 LAST CDS_LIB mstr_discrete
J 0
(-8000 4325);
PAINT MONO (-8000 4325);
DISPLAY INVISIBLE (-8000 4325);
FORCEPROP 2 LAST CDS_LOCATION C8A9
J 0
(-7950 4425);
DISPLAY 0.617021 (-7950 4425);
PAINT AQUA (-7950 4425);
DISPLAY INVISIBLE (-7950 4425);
FORCEPROP 1 LAST PATH I218
J 0
(-7950 4475);
DISPLAY 0.978723 (-7950 4475);
PAINT WHITE (-7950 4475);
DISPLAY INVISIBLE (-7950 4475);
FORCEPROP 0 LAST ROOM PVNN_PCH_STBY
J 0
(-7950 4525);
DISPLAY 1.021277 (-7950 4525);
PAINT ORANGE (-7950 4525);
DISPLAY INVISIBLE (-7950 4525);
FORCEPROP 2 LAST SEC 1
J 0
(-7950 4525);
DISPLAY 0.680851 (-7950 4525);
PAINT MONO (-7950 4525);
DISPLAY INVISIBLE (-7950 4525);
FORCEPROP 2 LAST SEC_TYPE 0402LF
J 0
(-7950 4525);
DISPLAY 1.021277 (-7950 4525);
PAINT ORANGE (-7950 4525);
DISPLAY INVISIBLE (-7950 4525);
FORCEADD GND..1
(-8000 4075);
FORCEPROP 3 LASTPIN (-8000 4125) SIG_NAME GND\g
J 0
(-7990 4135);
DISPLAY 0.659574 (-7990 4135);
PAINT MONO (-7990 4135);
DISPLAY INVISIBLE (-7990 4135);
FORCEPROP 2 LAST ROOM PVNN_PCH_STBY
J 0
(-8575 4150);
DISPLAY 1.361702 (-8575 4150);
PAINT ORANGE (-8575 4150);
DISPLAY INVISIBLE (-8575 4150);
FORCEPROP 1 LAST SIZE 1B
J 0
(-7925 4025);
DISPLAY 1.170213 (-7925 4025);
PAINT AQUA (-7925 4025);
DISPLAY INVISIBLE (-7925 4025);
FORCEPROP 1 LAST BODY_TYPE PLUMBING
J 0
(-8045 4032);
DISPLAY 0.340426 (-8045 4032);
PAINT GREEN (-8045 4032);
DISPLAY INVISIBLE (-8045 4032);
FORCEPROP 1 LAST PATH I219
J 0
(-7925 4075);
DISPLAY 0.872340 (-7925 4075);
PAINT AQUA (-7925 4075);
DISPLAY INVISIBLE (-7925 4075);
FORCEPROP 2 LAST CDS_LIB mstr_symbols
J 0
(-8000 4075);
PAINT MONO (-8000 4075);
DISPLAY INVISIBLE (-8000 4075);
FORCEPROP 1 LAST VOLTAGE 0
J 0
(-8000 4075);
PAINT SKYBLUE (-8000 4075);
DISPLAY INVISIBLE (-8000 4075);
FORCEPROP 1 LAST HDL_POWER GND
J 0
(-8000 4225);
DISPLAY 1.170213 (-8000 4225);
PAINT GREEN (-8000 4225);
DISPLAY INVISIBLE (-8000 4225);
FORCEADD RES..1
(-11800 4150);
FORCEPROP 1 LAST WATTAGE 1/16W
J 2
(-11825 4000);
DISPLAY 0.617021 (-11825 4000);
PAINT SKYBLUE (-11825 4000);
FORCEPROP 1 LAST TOLERANCE 5%
J 0
(-11850 4050);
DISPLAY 0.617021 (-11850 4050);
PAINT SKYBLUE (-11850 4050);
FORCEPROP 1 LAST VALUE 0.0
J 2
(-11900 4050);
DISPLAY 0.617021 (-11900 4050);
PAINT SKYBLUE (-11900 4050);
FORCEPROP 1 LAST MATERIAL CHIP
J 0
(-11800 4000);
DISPLAY 0.617021 (-11800 4000);
PAINT SKYBLUE (-11800 4000);
FORCEPROP 1 LAST PACK_TYPE 0402
J 0
(-11725 4050);
DISPLAY 0.617021 (-11725 4050);
PAINT SKYBLUE (-11725 4050);
FORCEPROP 1 LASTPIN (-11900 4150) $PN 1
J 0
(-11888 4162);
DISPLAY 0.617021 (-11888 4162);
PAINT ORANGE (-11888 4162);
FORCEPROP 1 LAST PART_NUMBER G21497-005
J 0
(-11950 4100);
DISPLAY 0.617021 (-11950 4100);
PAINT BLUE (-11950 4100);
FORCEPROP 1 LAST LOCATION R2L17
J 0
(-11850 4200);
DISPLAY 0.617021 (-11850 4200);
PAINT AQUA (-11850 4200);
FORCEPROP 1 LASTPIN (-11700 4150) $PN 2
J 0
(-11738 4162);
DISPLAY 0.617021 (-11738 4162);
PAINT ORANGE (-11738 4162);
FORCEPROP 2 LAST ROOM PVCCIN_CPU0_VR
J 0
(-11850 4250);
DISPLAY 1.361702 (-11850 4250);
PAINT ORANGE (-11850 4250);
DISPLAY INVISIBLE (-11850 4250);
FORCEPROP 2 LAST CDS_LOCATION R2L17
J 0
(-11850 4200);
DISPLAY 0.617021 (-11850 4200);
PAINT AQUA (-11850 4200);
DISPLAY INVISIBLE (-11850 4200);
FORCEPROP 2 LAST CDS_LIB mstr_discrete
J 0
(-11800 4150);
PAINT ORANGE (-11800 4150);
DISPLAY INVISIBLE (-11800 4150);
FORCEPROP 1 LAST PATH I221
J 0
(-11850 4300);
DISPLAY 0.978723 (-11850 4300);
PAINT WHITE (-11850 4300);
DISPLAY INVISIBLE (-11850 4300);
FORCEPROP 2 LAST SEC 1
J 0
(-11850 4350);
PAINT MONO (-11850 4350);
DISPLAY INVISIBLE (-11850 4350);
FORCEPROP 2 LAST SEC_TYPE 0402
J 0
(-11850 4350);
DISPLAY 1.021277 (-11850 4350);
PAINT ORANGE (-11850 4350);
DISPLAY INVISIBLE (-11850 4350);
FORCEADD RES..2
(-11175 5075);
FORCEPROP 1 LASTPIN (-11175 4975) $PN 2
J 0
(-11170 4985);
DISPLAY 0.617021 (-11170 4985);
PAINT ORANGE (-11170 4985);
FORCEPROP 1 LAST PACK_TYPE 0402
J 0
(-11135 4900);
DISPLAY 0.617021 (-11135 4900);
PAINT SKYBLUE (-11135 4900);
FORCEPROP 1 LAST WATTAGE 1/16W
J 0
(-11135 5050);
DISPLAY 0.617021 (-11135 5050);
PAINT SKYBLUE (-11135 5050);
FORCEPROP 1 LAST PART_NUMBER G21796-010
J 0
(-11135 4950);
DISPLAY 0.617021 (-11135 4950);
PAINT BLUE (-11135 4950);
FORCEPROP 1 LAST MATERIAL EMPTY
J 0
(-11135 5000);
DISPLAY 0.617021 (-11135 5000);
PAINT RED (-11135 5000);
FORCEPROP 1 LAST TOLERANCE 1%
J 0
(-11130 5100);
DISPLAY 0.617021 (-11130 5100);
PAINT SKYBLUE (-11130 5100);
FORCEPROP 1 LASTPIN (-11175 5175) $PN 1
J 0
(-11170 5137);
DISPLAY 0.617021 (-11170 5137);
PAINT ORANGE (-11170 5137);
FORCEPROP 1 LAST LOCATION R8A7
J 0
(-11130 5200);
DISPLAY 0.617021 (-11130 5200);
PAINT AQUA (-11130 5200);
FORCEPROP 1 LAST VALUE 100.0K
J 0
(-11130 5150);
DISPLAY 0.617021 (-11130 5150);
PAINT SKYBLUE (-11130 5150);
FORCEPROP 2 LAST CDS_LIB mstr_discrete
J 0
(-11175 5075);
PAINT ORANGE (-11175 5075);
DISPLAY INVISIBLE (-11175 5075);
FORCEPROP 0 LAST ROOM BMC
J 0
(-11125 5300);
DISPLAY 0.617021 (-11125 5300);
PAINT ORANGE (-11125 5300);
DISPLAY INVISIBLE (-11125 5300);
FORCEPROP 1 LAST PATH I222
J 0
(-11125 5250);
DISPLAY 0.978723 (-11125 5250);
PAINT WHITE (-11125 5250);
DISPLAY INVISIBLE (-11125 5250);
FORCEPROP 2 LAST CDS_LOCATION R8A7
J 0
(-11130 5200);
DISPLAY 0.617021 (-11130 5200);
PAINT AQUA (-11130 5200);
DISPLAY INVISIBLE (-11130 5200);
FORCEPROP 2 LAST SEC 1
J 0
(-11125 5300);
PAINT MONO (-11125 5300);
DISPLAY INVISIBLE (-11125 5300);
FORCEPROP 2 LAST SEC_TYPE 0402
J 0
(-11125 5300);
DISPLAY 1.021277 (-11125 5300);
PAINT ORANGE (-11125 5300);
DISPLAY INVISIBLE (-11125 5300);
FORCEPROP 0 LAST BOM_COST SM_CONTROLLER
J 0
(-11125 5400);
DISPLAY 1.021277 (-11125 5400);
PAINT ORANGE (-11125 5400);
DISPLAY INVISIBLE (-11125 5400);
FORCEADD RES..1
(-12350 4650);
FORCEPROP 1 LAST WATTAGE 1/16W
J 2
(-12375 4500);
DISPLAY 0.617021 (-12375 4500);
PAINT SKYBLUE (-12375 4500);
FORCEPROP 1 LAST TOLERANCE 5%
J 0
(-12400 4550);
DISPLAY 0.617021 (-12400 4550);
PAINT SKYBLUE (-12400 4550);
FORCEPROP 1 LAST VALUE 0.0
J 2
(-12450 4550);
DISPLAY 0.617021 (-12450 4550);
PAINT SKYBLUE (-12450 4550);
FORCEPROP 1 LASTPIN (-12450 4650) $PN 1
J 0
(-12438 4662);
DISPLAY 0.617021 (-12438 4662);
PAINT ORANGE (-12438 4662);
FORCEPROP 1 LASTPIN (-12250 4650) $PN 2
J 0
(-12288 4662);
DISPLAY 0.617021 (-12288 4662);
PAINT ORANGE (-12288 4662);
FORCEPROP 1 LAST MATERIAL CHIP
J 0
(-12350 4500);
DISPLAY 0.617021 (-12350 4500);
PAINT SKYBLUE (-12350 4500);
FORCEPROP 1 LAST PART_NUMBER G21497-005
J 0
(-12500 4600);
DISPLAY 0.617021 (-12500 4600);
PAINT BLUE (-12500 4600);
FORCEPROP 1 LAST LOCATION R2L1
J 0
(-12400 4700);
DISPLAY 0.617021 (-12400 4700);
PAINT AQUA (-12400 4700);
FORCEPROP 1 LAST PACK_TYPE 0402
J 0
(-12275 4550);
DISPLAY 0.617021 (-12275 4550);
PAINT SKYBLUE (-12275 4550);
FORCEPROP 2 LAST ROOM PVCCIN_CPU0_VR
J 0
(-12400 4750);
DISPLAY 1.361702 (-12400 4750);
PAINT ORANGE (-12400 4750);
DISPLAY INVISIBLE (-12400 4750);
FORCEPROP 1 LAST PATH I224
J 0
(-12400 4800);
DISPLAY 0.978723 (-12400 4800);
PAINT WHITE (-12400 4800);
DISPLAY INVISIBLE (-12400 4800);
FORCEPROP 2 LAST CDS_LOCATION R2L1
J 0
(-12400 4700);
DISPLAY 0.617021 (-12400 4700);
PAINT AQUA (-12400 4700);
DISPLAY INVISIBLE (-12400 4700);
FORCEPROP 2 LAST CDS_LIB mstr_discrete
J 0
(-12350 4650);
PAINT ORANGE (-12350 4650);
DISPLAY INVISIBLE (-12350 4650);
FORCEPROP 2 LAST SEC 1
J 0
(-12400 4850);
PAINT MONO (-12400 4850);
DISPLAY INVISIBLE (-12400 4850);
FORCEPROP 2 LAST SEC_TYPE 0402
J 0
(-12400 4850);
DISPLAY 1.021277 (-12400 4850);
PAINT ORANGE (-12400 4850);
DISPLAY INVISIBLE (-12400 4850);
FORCEADD RES..1
(-11525 2925);
FORCEPROP 1 LAST VALUE 0.0
J 2
(-11625 2825);
DISPLAY 0.617021 (-11625 2825);
PAINT SKYBLUE (-11625 2825);
FORCEPROP 1 LAST WATTAGE 1/16W
J 2
(-11550 2775);
DISPLAY 0.617021 (-11550 2775);
PAINT SKYBLUE (-11550 2775);
FORCEPROP 1 LAST MATERIAL CHIP
J 0
(-11525 2775);
DISPLAY 0.617021 (-11525 2775);
PAINT SKYBLUE (-11525 2775);
FORCEPROP 1 LAST LOCATION R2L7
J 0
(-11575 2975);
DISPLAY 0.617021 (-11575 2975);
PAINT AQUA (-11575 2975);
FORCEPROP 1 LAST TOLERANCE 5%
J 0
(-11575 2825);
DISPLAY 0.617021 (-11575 2825);
PAINT SKYBLUE (-11575 2825);
FORCEPROP 1 LAST PART_NUMBER G21497-005
J 0
(-11675 2875);
DISPLAY 0.617021 (-11675 2875);
PAINT BLUE (-11675 2875);
FORCEPROP 1 LAST PACK_TYPE 0402
J 0
(-11450 2825);
DISPLAY 0.617021 (-11450 2825);
PAINT SKYBLUE (-11450 2825);
FORCEPROP 2 LAST CDS_LIB mstr_discrete
J 0
(-11525 2925);
PAINT ORANGE (-11525 2925);
DISPLAY INVISIBLE (-11525 2925);
FORCEPROP 2 LAST CDS_LOCATION R2L7
J 0
(-11575 2975);
DISPLAY 0.617021 (-11575 2975);
PAINT AQUA (-11575 2975);
DISPLAY INVISIBLE (-11575 2975);
FORCEPROP 1 LASTPIN (-11625 2925) $PN 1
J 0
(-11613 2937);
DISPLAY 0.787234 (-11613 2937);
PAINT ORANGE (-11613 2937);
DISPLAY INVISIBLE (-11613 2937);
FORCEPROP 1 LASTPIN (-11425 2925) $PN 2
J 0
(-11463 2937);
DISPLAY 0.787234 (-11463 2937);
PAINT ORANGE (-11463 2937);
DISPLAY INVISIBLE (-11463 2937);
FORCEPROP 2 LAST ROOM PVCCIN_CPU0_VR
J 0
(-11575 3025);
DISPLAY 1.361702 (-11575 3025);
PAINT ORANGE (-11575 3025);
DISPLAY INVISIBLE (-11575 3025);
FORCEPROP 2 LAST CDS_SEC 1
J 0
(-11575 3125);
PAINT MONO (-11575 3125);
DISPLAY INVISIBLE (-11575 3125);
FORCEPROP 2 LAST $SEC 1
J 0
(-11575 3125);
PAINT MONO (-11575 3125);
DISPLAY INVISIBLE (-11575 3125);
FORCEPROP 1 LAST PATH I225
J 0
(-11575 3075);
DISPLAY 0.978723 (-11575 3075);
PAINT WHITE (-11575 3075);
DISPLAY INVISIBLE (-11575 3075);
FORCEADD OFFPAGE..1
(-13325 4650);
FORCEPROP 2 LAST $XR0 235 
J 0
(-13577 4650);
DISPLAY 0.638298 (-13577 4650);
PAINT MONO (-13577 4650);
FORCEPROP 2 LAST ROOM PVNN_PCH_STBY
J 0
(-13875 4725);
DISPLAY 1.361702 (-13875 4725);
PAINT ORANGE (-13875 4725);
DISPLAY INVISIBLE (-13875 4725);
FORCEPROP 2 LAST CDS_LIB mstr_standard
J 0
(-13325 4650);
PAINT ORANGE (-13325 4650);
DISPLAY INVISIBLE (-13325 4650);
FORCEPROP 1 LAST COMMENT_BODY TRUE
J 0
(-13200 4550);
DISPLAY 1.170213 (-13200 4550);
PAINT GREEN (-13200 4550);
DISPLAY INVISIBLE (-13200 4550);
FORCEPROP 1 LAST OFFPAGE TRUE
J 0
(-13000 4525);
DISPLAY 1.170213 (-13000 4525);
PAINT GREEN (-13000 4525);
DISPLAY INVISIBLE (-13000 4525);
FORCEPROP 2 LAST PATH I226
J 0
(-13275 4725);
DISPLAY 1.021277 (-13275 4725);
PAINT ORANGE (-13275 4725);
DISPLAY INVISIBLE (-13275 4725);
FORCEADD OFFPAGE..1
(-12600 2925);
FORCEPROP 2 LAST $XR0 235 
J 0
(-12852 2925);
DISPLAY 0.638298 (-12852 2925);
PAINT MONO (-12852 2925);
FORCEPROP 2 LAST ROOM PVNN_PCH_STBY
J 0
(-13150 3000);
DISPLAY 1.361702 (-13150 3000);
PAINT ORANGE (-13150 3000);
DISPLAY INVISIBLE (-13150 3000);
FORCEPROP 2 LAST CDS_LIB mstr_standard
J 0
(-12600 2925);
PAINT ORANGE (-12600 2925);
DISPLAY INVISIBLE (-12600 2925);
FORCEPROP 2 LAST PATH I227
J 0
(-12550 3000);
DISPLAY 1.021277 (-12550 3000);
PAINT ORANGE (-12550 3000);
DISPLAY INVISIBLE (-12550 3000);
FORCEPROP 1 LAST COMMENT_BODY TRUE
J 0
(-12475 2825);
DISPLAY 1.170213 (-12475 2825);
PAINT GREEN (-12475 2825);
DISPLAY INVISIBLE (-12475 2825);
FORCEPROP 1 LAST OFFPAGE TRUE
J 0
(-12275 2800);
DISPLAY 1.170213 (-12275 2800);
PAINT GREEN (-12275 2800);
DISPLAY INVISIBLE (-12275 2800);
FORCEADD VCC_CORE..1
(-12325 5750);
FORCEPROP 3 LASTPIN (-12325 5700) SIG_NAME VR_FET_SW_P12V_STBY_PVDDQ_DEF\g
J 0
(-12315 5710);
DISPLAY 0.659574 (-12315 5710);
PAINT MONO (-12315 5710);
DISPLAY INVISIBLE (-12315 5710);
FORCEPROP 1 LAST HDL_POWER VR_FET_SW_P12V_STBY_PVDDQ_DEF
J 1
(-12325 5800);
DISPLAY 0.617021 (-12325 5800);
PAINT GREEN (-12325 5800);
FORCEPROP 2 LAST CDS_LIB mstr_symbols
J 0
(-12325 5750);
PAINT ORANGE (-12325 5750);
DISPLAY INVISIBLE (-12325 5750);
FORCEPROP 1 LAST PATH I228
J 0
(-12275 5775);
DISPLAY 0.872340 (-12275 5775);
PAINT AQUA (-12275 5775);
DISPLAY INVISIBLE (-12275 5775);
FORCEADD PXE1110B..1
(-9725 3750);
FORCEPROP 2 LASTPIN (-10175 3550) $PN 20
J 2
(-10185 3560);
DISPLAY 0.617021 (-10185 3560);
PAINT ORANGE (-10185 3560);
FORCEPROP 2 LASTPIN (-10175 3600) $PN 19
J 2
(-10185 3610);
DISPLAY 0.617021 (-10185 3610);
PAINT ORANGE (-10185 3610);
FORCEPROP 2 LASTPIN (-10175 3100) $PN 25
J 2
(-10185 3110);
DISPLAY 0.617021 (-10185 3110);
PAINT ORANGE (-10185 3110);
FORCEPROP 2 LASTPIN (-10175 3050) $PN 26
J 2
(-10185 3060);
DISPLAY 0.617021 (-10185 3060);
PAINT ORANGE (-10185 3060);
FORCEPROP 2 LASTPIN (-10175 3200) $PN 34
J 2
(-10185 3210);
DISPLAY 0.617021 (-10185 3210);
PAINT ORANGE (-10185 3210);
FORCEPROP 2 LASTPIN (-10175 3450) $PN 30
J 2
(-10185 3460);
DISPLAY 0.617021 (-10185 3460);
PAINT ORANGE (-10185 3460);
FORCEPROP 2 LASTPIN (-10175 3500) $PN 29
J 2
(-10185 3510);
DISPLAY 0.617021 (-10185 3510);
PAINT ORANGE (-10185 3510);
FORCEPROP 2 LASTPIN (-10175 4000) $PN 38
J 2
(-10185 4010);
DISPLAY 0.617021 (-10185 4010);
PAINT ORANGE (-10185 4010);
FORCEPROP 2 LASTPIN (-10175 3900) $PN 40
J 2
(-10185 3910);
DISPLAY 0.617021 (-10185 3910);
PAINT ORANGE (-10185 3910);
FORCEPROP 2 LASTPIN (-10175 3850) $PN 16
J 2
(-10185 3860);
DISPLAY 0.617021 (-10185 3860);
PAINT ORANGE (-10185 3860);
FORCEPROP 2 LASTPIN (-10175 4050) $PN 37
J 2
(-10185 4060);
DISPLAY 0.617021 (-10185 4060);
PAINT ORANGE (-10185 4060);
FORCEPROP 2 LASTPIN (-10175 3000) $PN 36
J 2
(-10185 3010);
DISPLAY 0.617021 (-10185 3010);
PAINT ORANGE (-10185 3010);
FORCEPROP 2 LASTPIN (-10175 2950) $PN 33
J 2
(-10185 2960);
DISPLAY 0.617021 (-10185 2960);
PAINT ORANGE (-10185 2960);
FORCEPROP 1 LAST PART_NUMBER H89187-001
J 0
(-10125 2850);
DISPLAY 0.617021 (-10125 2850);
PAINT BLUE (-10125 2850);
FORCEPROP 2 LASTPIN (-10175 3300) $PN 7
J 2
(-10185 3310);
DISPLAY 0.617021 (-10185 3310);
PAINT ORANGE (-10185 3310);
FORCEPROP 2 LASTPIN (-10175 3350) $PN 6
J 2
(-10185 3360);
DISPLAY 0.617021 (-10185 3360);
PAINT ORANGE (-10185 3360);
FORCEPROP 2 LASTPIN (-10175 3700) $PN 8
J 2
(-10185 3710);
DISPLAY 0.617021 (-10185 3710);
PAINT ORANGE (-10185 3710);
FORCEPROP 2 LASTPIN (-9275 3300) $PN 1
J 0
(-9265 3310);
DISPLAY 0.617021 (-9265 3310);
PAINT ORANGE (-9265 3310);
FORCEPROP 2 LASTPIN (-9275 3350) $PN 2
J 0
(-9265 3360);
DISPLAY 0.617021 (-9265 3360);
PAINT ORANGE (-9265 3360);
FORCEPROP 2 LASTPIN (-9275 3400) $PN 4
J 0
(-9265 3410);
DISPLAY 0.617021 (-9265 3410);
PAINT ORANGE (-9265 3410);
FORCEPROP 2 LASTPIN (-9275 3900) $PN 5
J 0
(-9265 3910);
DISPLAY 0.617021 (-9265 3910);
PAINT ORANGE (-9265 3910);
FORCEPROP 2 LASTPIN (-9275 3950) $PN 3
J 0
(-9265 3960);
DISPLAY 0.617021 (-9265 3960);
PAINT ORANGE (-9265 3960);
FORCEPROP 2 LASTPIN (-9275 3450) $PN 24
J 0
(-9265 3460);
DISPLAY 0.617021 (-9265 3460);
PAINT ORANGE (-9265 3460);
FORCEPROP 2 LASTPIN (-9275 3500) $PN 28
J 0
(-9265 3510);
DISPLAY 0.617021 (-9265 3510);
PAINT ORANGE (-9265 3510);
FORCEPROP 2 LASTPIN (-9275 3000) $PN 27
J 0
(-9265 3010);
DISPLAY 0.617021 (-9265 3010);
PAINT ORANGE (-9265 3010);
FORCEPROP 2 LASTPIN (-9275 3050) $PN 23
J 0
(-9265 3060);
DISPLAY 0.617021 (-9265 3060);
PAINT ORANGE (-9265 3060);
FORCEPROP 2 LASTPIN (-9275 3600) $PN 13
J 0
(-9265 3610);
DISPLAY 0.617021 (-9265 3610);
PAINT ORANGE (-9265 3610);
FORCEPROP 2 LASTPIN (-9275 3650) $PN 14
J 0
(-9265 3660);
DISPLAY 0.617021 (-9265 3660);
PAINT ORANGE (-9265 3660);
FORCEPROP 2 LASTPIN (-9275 3700) $PN 18
J 0
(-9265 3710);
DISPLAY 0.617021 (-9265 3710);
PAINT ORANGE (-9265 3710);
FORCEPROP 2 LASTPIN (-9275 3750) $PN 31
J 0
(-9265 3760);
DISPLAY 0.617021 (-9265 3760);
PAINT ORANGE (-9265 3760);
FORCEPROP 2 LASTPIN (-9275 3800) $PN 32
J 0
(-9265 3810);
DISPLAY 0.617021 (-9265 3810);
PAINT ORANGE (-9265 3810);
FORCEPROP 2 LASTPIN (-9275 3200) $PN 41
J 0
(-9265 3210);
DISPLAY 0.617021 (-9265 3210);
PAINT ORANGE (-9265 3210);
FORCEPROP 2 LASTPIN (-9275 4050) $PN 17
J 0
(-9265 4060);
DISPLAY 0.617021 (-9265 4060);
PAINT ORANGE (-9265 4060);
FORCEPROP 2 LASTPIN (-10175 4350) $PN 21
J 2
(-10185 4360);
DISPLAY 0.617021 (-10185 4360);
PAINT ORANGE (-10185 4360);
FORCEPROP 2 LASTPIN (-10175 4300) $PN 22
J 2
(-10185 4310);
DISPLAY 0.617021 (-10185 4310);
PAINT ORANGE (-10185 4310);
FORCEPROP 2 LASTPIN (-10175 4200) $PN 35
J 2
(-10185 4210);
DISPLAY 0.617021 (-10185 4210);
PAINT ORANGE (-10185 4210);
FORCEPROP 2 LASTPIN (-10175 4150) $PN 10
J 2
(-10185 4160);
DISPLAY 0.617021 (-10185 4160);
PAINT ORANGE (-10185 4160);
FORCEPROP 2 LASTPIN (-10175 4450) $PN 15
J 2
(-10185 4460);
DISPLAY 0.617021 (-10185 4460);
PAINT ORANGE (-10185 4460);
FORCEPROP 2 LASTPIN (-10175 4500) $PN 39
J 2
(-10185 4510);
DISPLAY 0.617021 (-10185 4510);
PAINT ORANGE (-10185 4510);
FORCEPROP 1 LAST MATERIAL IC
J 0
(-10125 4625);
DISPLAY 0.617021 (-10125 4625);
PAINT SKYBLUE (-10125 4625);
FORCEPROP 1 LAST LOCATION EU8A1
J 0
(-10125 4675);
DISPLAY 0.617021 (-10125 4675);
PAINT AQUA (-10125 4675);
FORCEPROP 2 LASTPIN (-9275 4500) $PN 9
J 0
(-9265 4510);
DISPLAY 0.617021 (-9265 4510);
PAINT ORANGE (-9265 4510);
FORCEPROP 2 LASTPIN (-9275 4350) $PN 12
J 0
(-9265 4360);
DISPLAY 0.617021 (-9265 4360);
PAINT ORANGE (-9265 4360);
FORCEPROP 2 LASTPIN (-9275 4150) $PN 11
J 0
(-9265 4160);
DISPLAY 0.617021 (-9265 4160);
PAINT ORANGE (-9265 4160);
FORCEPROP 1 LAST CDS_LMAN_SYM_OUTLINE -400,850,400,-850
J 0
(-9725 3750);
DISPLAY 0.468085 (-9725 3750);
PAINT GREEN (-9725 3750);
DISPLAY INVISIBLE (-9725 3750);
FORCEPROP 2 LAST CDS_LIB mstr_controller
J 0
(-9725 3750);
PAINT ORANGE (-9725 3750);
DISPLAY INVISIBLE (-9725 3750);
FORCEPROP 1 LAST PACK_TYPE QFN
J 0
(-10125 4725);
PAINT SKYBLUE (-10125 4725);
DISPLAY INVISIBLE (-10125 4725);
FORCEPROP 2 LAST SEC_TYPE QFN
J 0
(-10125 4725);
DISPLAY 1.021277 (-10125 4725);
PAINT ORANGE (-10125 4725);
DISPLAY INVISIBLE (-10125 4725);
FORCEPROP 2 LAST SEC 1
J 0
(-10125 4725);
DISPLAY 0.680851 (-10125 4725);
PAINT MONO (-10125 4725);
DISPLAY INVISIBLE (-10125 4725);
FORCEPROP 2 LAST CDS_LOCATION EU8A1
J 0
(-10125 4675);
DISPLAY 0.617021 (-10125 4675);
PAINT AQUA (-10125 4675);
DISPLAY INVISIBLE (-10125 4675);
FORCEPROP 1 LAST PATH I229
J 0
(-9625 4626);
PAINT WHITE (-9625 4626);
DISPLAY INVISIBLE (-9625 4626);
FORCEADD OFFPAGE..1
R 2
(-7100 3600);
FORCEPROP 2 LAST $XR0 119 
J 0
(-6914 3600);
DISPLAY 0.638298 (-6914 3600);
PAINT MONO (-6914 3600);
FORCEPROP 1 LAST COMMENT_BODY TRUE
J 2
(-7225 3500);
DISPLAY 1.170213 (-7225 3500);
PAINT GREEN (-7225 3500);
DISPLAY INVISIBLE (-7225 3500);
FORCEPROP 1 LAST OFFPAGE TRUE
J 2
(-7425 3475);
DISPLAY 1.170213 (-7425 3475);
PAINT GREEN (-7425 3475);
DISPLAY INVISIBLE (-7425 3475);
FORCEPROP 2 LAST ROOM PVNN_PCH_STBY
J 0
(-7525 3675);
DISPLAY 1.361702 (-7525 3675);
PAINT ORANGE (-7525 3675);
DISPLAY INVISIBLE (-7525 3675);
FORCEPROP 2 LAST CDS_LIB mstr_standard
J 0
(-7100 3600);
PAINT ORANGE (-7100 3600);
DISPLAY INVISIBLE (-7100 3600);
FORCEPROP 2 LAST PATH I232
J 0
(-6925 3675);
DISPLAY 1.021277 (-6925 3675);
PAINT ORANGE (-6925 3675);
DISPLAY INVISIBLE (-6925 3675);
FORCEADD OFFPAGE..1
R 2
(-7125 3650);
FORCEPROP 2 LAST $XR0 119 
J 0
(-6939 3650);
DISPLAY 0.638298 (-6939 3650);
PAINT MONO (-6939 3650);
FORCEPROP 1 LAST OFFPAGE TRUE
J 2
(-7450 3525);
DISPLAY 1.170213 (-7450 3525);
PAINT GREEN (-7450 3525);
DISPLAY INVISIBLE (-7450 3525);
FORCEPROP 1 LAST COMMENT_BODY TRUE
J 2
(-7250 3550);
DISPLAY 1.170213 (-7250 3550);
PAINT GREEN (-7250 3550);
DISPLAY INVISIBLE (-7250 3550);
FORCEPROP 2 LAST ROOM PVNN_PCH_STBY
J 0
(-7550 3725);
DISPLAY 1.361702 (-7550 3725);
PAINT ORANGE (-7550 3725);
DISPLAY INVISIBLE (-7550 3725);
FORCEPROP 2 LAST CDS_LIB mstr_standard
J 0
(-7125 3650);
PAINT ORANGE (-7125 3650);
DISPLAY INVISIBLE (-7125 3650);
FORCEPROP 2 LAST PATH I234
J 0
(-6950 3725);
DISPLAY 1.021277 (-6950 3725);
PAINT ORANGE (-6950 3725);
DISPLAY INVISIBLE (-6950 3725);
FORCEADD RES..2
(-7775 4875);
FORCEPROP 1 LAST WATTAGE 1/16W
J 0
(-7735 4850);
DISPLAY 0.617021 (-7735 4850);
PAINT SKYBLUE (-7735 4850);
FORCEPROP 1 LAST PACK_TYPE 0402
J 0
(-7735 4700);
DISPLAY 0.617021 (-7735 4700);
PAINT SKYBLUE (-7735 4700);
FORCEPROP 1 LAST TOLERANCE 1%
J 0
(-7730 4900);
DISPLAY 0.617021 (-7730 4900);
PAINT SKYBLUE (-7730 4900);
FORCEPROP 1 LAST VALUE 100.0K
J 0
(-7730 4950);
DISPLAY 0.617021 (-7730 4950);
PAINT SKYBLUE (-7730 4950);
FORCEPROP 1 LAST PART_NUMBER G21796-010
J 0
(-7735 4750);
DISPLAY 0.617021 (-7735 4750);
PAINT BLUE (-7735 4750);
FORCEPROP 1 LAST LOCATION R2L25
J 0
(-7730 5000);
DISPLAY 0.617021 (-7730 5000);
PAINT AQUA (-7730 5000);
FORCEPROP 1 LAST MATERIAL EMPTY
J 0
(-7735 4800);
DISPLAY 0.617021 (-7735 4800);
PAINT RED (-7735 4800);
FORCEPROP 1 LASTPIN (-7775 4775) $PN 2
J 0
(-7770 4785);
DISPLAY 0.787234 (-7770 4785);
PAINT ORANGE (-7770 4785);
DISPLAY INVISIBLE (-7770 4785);
FORCEPROP 1 LASTPIN (-7775 4975) $PN 1
J 0
(-7770 4937);
DISPLAY 0.787234 (-7770 4937);
PAINT ORANGE (-7770 4937);
DISPLAY INVISIBLE (-7770 4937);
FORCEPROP 2 LAST CDS_LIB mstr_discrete
J 0
(-7775 4875);
PAINT ORANGE (-7775 4875);
DISPLAY INVISIBLE (-7775 4875);
FORCEPROP 1 LAST PATH I235
J 0
(-7725 5050);
DISPLAY 0.978723 (-7725 5050);
PAINT WHITE (-7725 5050);
DISPLAY INVISIBLE (-7725 5050);
FORCEPROP 0 LAST ROOM BMC
J 0
(-7725 5100);
DISPLAY 0.617021 (-7725 5100);
PAINT ORANGE (-7725 5100);
DISPLAY INVISIBLE (-7725 5100);
FORCEPROP 2 LAST $SEC 1
J 0
(-7725 5100);
PAINT MONO (-7725 5100);
DISPLAY INVISIBLE (-7725 5100);
FORCEPROP 2 LAST CDS_SEC 1
J 0
(-7725 5100);
PAINT MONO (-7725 5100);
DISPLAY INVISIBLE (-7725 5100);
FORCEPROP 0 LAST BOM_COST SM_CONTROLLER
J 0
(-7725 5200);
DISPLAY 1.021277 (-7725 5200);
PAINT ORANGE (-7725 5200);
DISPLAY INVISIBLE (-7725 5200);
FORCEADD RES..2
(-7450 4950);
FORCEPROP 1 LAST PACK_TYPE 0402
J 0
(-7410 4775);
DISPLAY 0.617021 (-7410 4775);
PAINT SKYBLUE (-7410 4775);
FORCEPROP 1 LAST TOLERANCE 1%
J 0
(-7405 4975);
DISPLAY 0.617021 (-7405 4975);
PAINT SKYBLUE (-7405 4975);
FORCEPROP 1 LAST WATTAGE 1/16W
J 0
(-7410 4925);
DISPLAY 0.617021 (-7410 4925);
PAINT SKYBLUE (-7410 4925);
FORCEPROP 1 LAST VALUE 100.0K
J 0
(-7405 5025);
DISPLAY 0.617021 (-7405 5025);
PAINT SKYBLUE (-7405 5025);
FORCEPROP 1 LAST LOCATION R2L26
J 0
(-7405 5075);
DISPLAY 0.617021 (-7405 5075);
PAINT AQUA (-7405 5075);
FORCEPROP 1 LAST MATERIAL EMPTY
J 0
(-7410 4875);
DISPLAY 0.617021 (-7410 4875);
PAINT RED (-7410 4875);
FORCEPROP 1 LAST PART_NUMBER G21796-010
J 0
(-7410 4825);
DISPLAY 0.617021 (-7410 4825);
PAINT BLUE (-7410 4825);
FORCEPROP 1 LASTPIN (-7450 4850) $PN 2
J 0
(-7445 4860);
DISPLAY 0.787234 (-7445 4860);
PAINT ORANGE (-7445 4860);
DISPLAY INVISIBLE (-7445 4860);
FORCEPROP 2 LAST CDS_LIB mstr_discrete
J 0
(-7450 4950);
PAINT ORANGE (-7450 4950);
DISPLAY INVISIBLE (-7450 4950);
FORCEPROP 1 LASTPIN (-7450 5050) $PN 1
J 0
(-7445 5012);
DISPLAY 0.787234 (-7445 5012);
PAINT ORANGE (-7445 5012);
DISPLAY INVISIBLE (-7445 5012);
FORCEPROP 0 LAST BOM_COST SM_CONTROLLER
J 0
(-7400 5275);
DISPLAY 1.021277 (-7400 5275);
PAINT ORANGE (-7400 5275);
DISPLAY INVISIBLE (-7400 5275);
FORCEPROP 2 LAST CDS_SEC 1
J 0
(-7400 5175);
PAINT MONO (-7400 5175);
DISPLAY INVISIBLE (-7400 5175);
FORCEPROP 2 LAST $SEC 1
J 0
(-7400 5175);
PAINT MONO (-7400 5175);
DISPLAY INVISIBLE (-7400 5175);
FORCEPROP 1 LAST PATH I236
J 0
(-7400 5125);
DISPLAY 0.978723 (-7400 5125);
PAINT WHITE (-7400 5125);
DISPLAY INVISIBLE (-7400 5125);
FORCEPROP 0 LAST ROOM BMC
J 0
(-7400 5175);
DISPLAY 0.617021 (-7400 5175);
PAINT ORANGE (-7400 5175);
DISPLAY INVISIBLE (-7400 5175);
FORCEADD DNS..2
(-7770 4870);
PAINT RED (-7770 4870);
FORCEPROP 1 LAST COMMENT_BODY TRUE
R 1
J 0
(-7695 4645);
DISPLAY 0.872340 (-7695 4645);
PAINT GREEN (-7695 4645);
DISPLAY INVISIBLE (-7695 4645);
FORCEPROP 2 LAST CDS_LIB mstr_misc
J 0
(-7770 4870);
PAINT ORANGE (-7770 4870);
DISPLAY INVISIBLE (-7770 4870);
FORCEADD INTEL_CORP_BPAGE..1
(-5800 1000);
FORCEPROP 1 LAST CDS_CON_LAST_MODIFIED Tue Dec 01 11:52:30 2015
J 0
(-7225 1325);
PAINT ORANGE (-7225 1325);
DISPLAY INVISIBLE (-7225 1325);
FORCEPROP 1 LAST CUSTOM_TXT_CDS <CURRENT_DESIGN_SHEET> OF <TOTAL_DESIGN_SHEETS>
J 0
(-6300 1025);
PAINT GREEN (-6300 1025);
FORCEPROP 1 LAST CUSTOM_TXT_CDS <CON_LAST_MODIFIED>
J 0
(-7725 1350);
PAINT GREEN (-7725 1350);
FORCEPROP 2 LAST CUSTOM_TXT_CDS <XR_PAGE_TITLE>
J 0
(-13690 6250);
DISPLAY 0.638298 (-13690 6250);
PAINT PINK (-13690 6250);
DISPLAY INVISIBLE (-13690 6250);
FORCEPROP 1 LAST SCH_TITLE PVNN P1V05 PCH STBY VR (1 OF 2)
J 0
(-13650 1125);
DISPLAY 1.212766 (-13650 1125);
PAINT ORANGE (-13650 1125);
FORCEPROP 1 LAST SCH_ADDRESS2 P.O. BOX 58119
J 0
(-9775 1075);
DISPLAY 0.617021 (-9775 1075);
PAINT GREEN (-9775 1075);
FORCEPROP 1 LAST SCH_ADDRESS1 2200 Mission College Blvd.
J 0
(-9775 1125);
DISPLAY 0.617021 (-9775 1125);
PAINT GREEN (-9775 1125);
FORCEPROP 1 LAST SCH_ADDRESS3 Santa Clara, CA 95052-8119
J 0
(-9775 1025);
DISPLAY 0.617021 (-9775 1025);
PAINT GREEN (-9775 1025);
FORCEPROP 1 LAST SCH_NUMBER H4694802
J 0
(-7100 1150);
DISPLAY 1.212766 (-7100 1150);
PAINT YELLOW (-7100 1150);
FORCEPROP 1 LAST SCH_DEPT BESD
J 1
(-10250 1100);
DISPLAY 1.212766 (-10250 1100);
PAINT YELLOW (-10250 1100);
FORCEPROP 1 LAST SCH_REV 2.420
J 0
(-6050 1150);
DISPLAY 0.978723 (-6050 1150);
PAINT YELLOW (-6050 1150);
FORCEPROP 2 LAST PAGE_BORDER TRUE
J 0
(-13690 6250);
DISPLAY 0.851064 (-13690 6250);
PAINT PINK (-13690 6250);
DISPLAY INVISIBLE (-13690 6250);
FORCEPROP 2 LAST CDS_LIB mstr_symbols
J 0
(-5800 1000);
PAINT ORANGE (-5800 1000);
DISPLAY INVISIBLE (-5800 1000);
FORCEPROP 1 LAST COMMENT_BODY TRUE
J 0
(-5788 1012);
DISPLAY 0.468085 (-5788 1012);
PAINT GREEN (-5788 1012);
DISPLAY INVISIBLE (-5788 1012);
FORCEPROP 2 LAST CDS_XR_PAGE_TITLE CR-235 : @BASEBOARD_FAB2_LIB.BASEBOARD_FAB2(SCH_1):PAGE235
J 0
(-13690 6250);
DISPLAY 0.638298 (-13690 6250);
PAINT PINK (-13690 6250);
DISPLAY INVISIBLE (-13690 6250);
FORCEADD DESIGN_NOTE..1
(-7050 2200);
FORCEPROP 0 LAST L2 AVID0
J 0
(-7250 1950);
PAINT WHITE (-7250 1950);
FORCEPROP 0 LAST L22 1
J 0
(-7150 1650);
PAINT WHITE (-7150 1650);
FORCEPROP 0 LAST L14 0
J 0
(-7150 1750);
PAINT WHITE (-7150 1750);
FORCEPROP 0 LAST L3 AVID1
J 0
(-6900 1950);
PAINT WHITE (-6900 1950);
FORCEPROP 0 LAST L30 1
J 0
(-7150 1550);
PAINT WHITE (-7150 1550);
FORCEPROP 0 LAST L23 0
J 0
(-6800 1650);
PAINT WHITE (-6800 1650);
FORCEPROP 0 LAST L31 1
J 0
(-6800 1575);
PAINT WHITE (-6800 1575);
FORCEPROP 0 LAST L7 0
J 0
(-6800 1850);
PAINT WHITE (-6800 1850);
FORCEPROP 0 LAST L15 1
J 0
(-6800 1775);
PAINT WHITE (-6800 1775);
FORCEPROP 0 LAST L6 0
J 0
(-7150 1850);
PAINT WHITE (-7150 1850);
FORCEPROP 0 LAST L33 1.000 V
J 0
(-6500 1550);
PAINT WHITE (-6500 1550);
FORCEPROP 0 LAST L9 0.850 V
J 0
(-6500 1850);
PAINT WHITE (-6500 1850);
FORCEPROP 0 LAST L17 0.900 V
J 0
(-6500 1750);
PAINT WHITE (-6500 1750);
FORCEPROP 0 LAST L25 0.950 V
J 0
(-6500 1650);
PAINT WHITE (-6500 1650);
FORCEPROP 0 LAST L1 OUTPUT VOLTAGE AVID
J 0
(-7250 2075);
PAINT WHITE (-7250 2075);
FORCEPROP 0 LAST L5 OUTPUT VOLTAGE
J 0
(-6525 1950);
PAINT WHITE (-6525 1950);
FORCEPROP 1 LAST COMMENT_BODY TRUE
J 0
(-7025 2300);
DISPLAY 1.319149 (-7025 2300);
PAINT ORANGE (-7025 2300);
DISPLAY INVISIBLE (-7025 2300);
FORCEPROP 2 LAST CDS_LIB mstr_symbols
J 0
(-7050 2200);
PAINT ORANGE (-7050 2200);
DISPLAY INVISIBLE (-7050 2200);
FORCEADD DNS..2
(-7445 4945);
PAINT RED (-7445 4945);
FORCEPROP 1 LAST COMMENT_BODY TRUE
R 1
J 0
(-7370 4720);
DISPLAY 0.872340 (-7370 4720);
PAINT GREEN (-7370 4720);
DISPLAY INVISIBLE (-7370 4720);
FORCEPROP 2 LAST CDS_LIB mstr_misc
J 0
(-7445 4945);
PAINT ORANGE (-7445 4945);
DISPLAY INVISIBLE (-7445 4945);
FORCEADD DNS..2
(-11170 5070);
PAINT RED (-11170 5070);
FORCEPROP 1 LAST COMMENT_BODY TRUE
R 1
J 0
(-11095 4845);
DISPLAY 0.872340 (-11095 4845);
PAINT GREEN (-11095 4845);
DISPLAY INVISIBLE (-11095 4845);
FORCEPROP 2 LAST CDS_LIB mstr_misc
J 0
(-11170 5070);
PAINT ORANGE (-11170 5070);
DISPLAY INVISIBLE (-11170 5070);
FORCEADD DESIGN_NOTE..1
(-10100 2675);
FORCEPROP 0 LAST L1 SMBUS ADDRESS: 0XD0
J 0
(-10300 2550);
DISPLAY 1.021277 (-10300 2550);
PAINT ORANGE (-10300 2550);
FORCEPROP 2 LAST CDS_LIB mstr_symbols
J 0
(-10100 2675);
PAINT ORANGE (-10100 2675);
DISPLAY INVISIBLE (-10100 2675);
FORCEPROP 1 LAST COMMENT_BODY TRUE
J 0
(-10075 2775);
DISPLAY 0.978723 (-10075 2775);
PAINT ORANGE (-10075 2775);
DISPLAY INVISIBLE (-10075 2775);
FORCEADD DNS..2
(-8520 4795);
PAINT RED (-8520 4795);
FORCEPROP 1 LAST COMMENT_BODY TRUE
R 1
J 0
(-8445 4570);
DISPLAY 0.872340 (-8445 4570);
PAINT GREEN (-8445 4570);
DISPLAY INVISIBLE (-8445 4570);
FORCEPROP 2 LAST CDS_LIB mstr_misc
J 0
(-8520 4795);
PAINT ORANGE (-8520 4795);
DISPLAY INVISIBLE (-8520 4795);
WIRE 16 -1 (-7450 5175)(-7775 5175);
WIRE 16 -1 (-7450 5175)(-7450 5050);
WIRE 16 -1 (-7775 5175)(-7775 4975);
WIRE 16 -1 (-8200 5175)(-7775 5175);
WIRE 16 -1 (-8200 4975)(-8200 5175);
WIRE 16 -1 (-8200 5175)(-8375 5175);
WIRE 16 -1 (-8375 5175)(-8525 5175);
WIRE 16 -1 (-8375 5325)(-8375 5175);
WIRE 16 -1 (-9025 5175)(-8525 5175);
WIRE 16 -1 (-8525 4900)(-8525 5175);
WIRE 16 -1 (-9025 4975)(-9025 5175);
WIRE 16 -1 (-8800 1600)(-8800 1825);
WIRE 16 -1 (-9200 1825)(-9200 1875);
WIRE 16 -1 (-9750 4925)(-9750 4975);
WIRE 16 -1 (-9275 3200)(-8900 3200);
WIRE 16 -1 (-8900 3050)(-8900 3200);
WIRE 16 -1 (-9275 3050)(-8900 3050);
WIRE 16 -1 (-8900 3050)(-8900 3000);
WIRE 16 -1 (-9275 3000)(-8900 3000);
WIRE 16 -1 (-8900 3000)(-8900 2850);
WIRE 16 -1 (-11175 5175)(-11175 5600);
WIRE 16 -1 (-11175 5600)(-10450 5600);
WIRE 16 -1 (-10450 5525)(-10450 5600);
WIRE 16 -1 (-10450 5600)(-10450 5700);
WIRE 16 -1 (-10150 4925)(-10150 4975);
WIRE 16 -1 (-10375 2175)(-10375 1975);
WIRE 16 -1 (-10375 1975)(-10750 1975);
WIRE 16 -1 (-10750 2150)(-10750 1975);
WIRE 16 -1 (-10750 1975)(-10750 1725);
WIRE 16 -1 (-12325 4975)(-12325 5075);
WIRE 16 -1 (-12550 4975)(-12550 5075);
WIRE 16 -1 (-8000 4225)(-8000 4125);
WIRE 16 -1 (-12325 5600)(-12325 5700);
WIRE 16 -1 (-12325 5350)(-12325 5400);
WIRE 16 -1 (-12325 5275)(-12325 5350);
WIRE 16 -1 (-12325 5350)(-12550 5350);
WIRE 16 -1 (-12550 5275)(-12550 5350);
WIRE 16 -1 (-12550 5350)(-13100 5350);
FORCEPROP 2 LAST SIG_NAME VR_PVNN_PCH_VINSEN
J 0
(-13115 5365);
DISPLAY 0.617021 (-13115 5365);
PAINT ORANGE (-13115 5365);
WIRE 16 682 (-5950 5350)(-5950 5925);
WIRE 16 682 (-6850 5350)(-5950 5350);
WIRE 16 682 (-5950 5925)(-6850 5925);
WIRE 16 682 (-6850 5925)(-6850 5350);
WIRE 16 682 (-6975 5350)(-6975 5925);
WIRE 16 682 (-7875 5350)(-6975 5350);
WIRE 16 682 (-6975 5925)(-7875 5925);
WIRE 16 682 (-7875 5925)(-7875 5350);
WIRE 16 -1 (-7000 4500)(-6325 4500);
FORCEPROP 2 LAST SIG_NAME PWRGD_PVNN_P1V05_PCH
J 0
(-6900 4515);
DISPLAY 0.617021 (-6900 4515);
PAINT ORANGE (-6900 4515);
WIRE 16 -1 (-8000 4425)(-8000 4500);
WIRE 16 -1 (-7200 4500)(-8000 4500);
WIRE 16 -1 (-9025 4500)(-8000 4500);
FORCEPROP 2 LAST SIG_NAME PWRGD_PVNN_PCH_R
J 0
(-8990 4515);
DISPLAY 0.617021 (-8990 4515);
PAINT ORANGE (-8990 4515);
FORCEPROP 2 LASTPROP $XRERR UNIQUE?
J 0
(-9230 4515);
DISPLAY 0.638298 (-9230 4515);
PAINT MONO (-9230 4515);
DISPLAY INVISIBLE (-9230 4515);
WIRE 16 -1 (-9025 4775)(-9025 4500);
WIRE 16 -1 (-9275 4500)(-9025 4500);
WIRE 16 -1 (-7150 3600)(-7450 3600);
WIRE 16 -1 (-7450 4850)(-7450 3600);
WIRE 16 -1 (-9275 3600)(-7450 3600);
FORCEPROP 2 LAST SIG_NAME VID_PCH_CORE_PVNN_AUX_VID_0
J 0
(-9100 3615);
DISPLAY 0.617021 (-9100 3615);
PAINT ORANGE (-9100 3615);
WIRE 16 -1 (-7175 3650)(-7775 3650);
WIRE 16 -1 (-7775 4775)(-7775 3650);
WIRE 16 -1 (-9275 3650)(-7775 3650);
FORCEPROP 2 LAST SIG_NAME VID_PCH_CORE_PVNN_AUX_VID_1
J 0
(-9100 3665);
DISPLAY 0.617021 (-9100 3665);
PAINT ORANGE (-9100 3665);
WIRE 16 -1 (-5950 1475)(-5950 2025);
WIRE 16 -1 (-7300 1475)(-5950 1475);
WIRE 16 -1 (-5950 2025)(-7300 2025);
WIRE 16 -1 (-7300 2025)(-7300 1475);
WIRE 16 -1 (-7275 1525)(-6025 1525);
WIRE 16 -1 (-7275 1725)(-6025 1725);
WIRE 16 -1 (-7275 1625)(-6025 1625);
WIRE 16 -1 (-7275 1925)(-6025 1925);
WIRE 16 -1 (-7275 1825)(-6025 1825);
WIRE 16 -1 (-6600 2000)(-6600 1500);
WIRE 16 -1 (-7000 2000)(-7000 1500);
WIRE 16 -1 (-8800 2150)(-8150 2150);
FORCEPROP 2 LAST SIG_NAME VR_PVNN_P1V05_PCH_VD12
J 2
(-8226 2153);
DISPLAY 0.617021 (-8226 2153);
PAINT ORANGE (-8226 2153);
WIRE 16 -1 (-8800 2150)(-9200 2150);
WIRE 16 -1 (-8800 2025)(-8800 2150);
WIRE 16 -1 (-9200 2075)(-9200 2150);
WIRE 16 -1 (-7175 3900)(-9275 3900);
FORCEPROP 2 LAST SIG_NAME VR_PVNN_PCH_PWM1
J 0
(-8300 3915);
DISPLAY 0.617021 (-8300 3915);
PAINT ORANGE (-8300 3915);
WIRE 16 -1 (-7175 3950)(-9275 3950);
FORCEPROP 2 LAST SIG_NAME VR_P1V05_PCH_STBY_PWM1
J 0
(-8325 3974);
DISPLAY 0.617021 (-8325 3974);
PAINT ORANGE (-8325 3974);
WIRE 16 -1 (-8200 4150)(-8200 4775);
WIRE 16 -1 (-8200 4150)(-9275 4150);
FORCEPROP 2 LAST SIG_NAME IRQ_PVNN_PCH_VRHOT_N
J 0
(-9175 4165);
DISPLAY 0.617021 (-9175 4165);
PAINT ORANGE (-9175 4165);
FORCEPROP 2 LASTPROP $XRERR UNIQUE?
J 0
(-9415 4165);
DISPLAY 0.638298 (-9415 4165);
PAINT MONO (-9415 4165);
DISPLAY INVISIBLE (-9415 4165);
WIRE 16 -1 (-9275 4350)(-8650 4350);
FORCEPROP 2 LAST SIG_NAME TP_PVNN_PCH_PINALRT_N
J 0
(-9175 4365);
DISPLAY 0.617021 (-9175 4365);
PAINT ORANGE (-9175 4365);
FORCEPROP 2 LASTPROP $XRERR UNIQUE?
J 0
(-8620 4350);
DISPLAY 0.638298 (-8620 4350);
PAINT MONO (-8620 4350);
DISPLAY INVISIBLE (-8620 4350);
WIRE 16 -1 (-9750 5175)(-9750 5225);
WIRE 16 -1 (-9750 5225)(-10150 5225);
WIRE 16 -1 (-10150 5175)(-10150 5225);
WIRE 16 -1 (-10150 5225)(-10450 5225);
WIRE 16 -1 (-10450 5325)(-10450 5225);
WIRE 16 -1 (-10450 5225)(-10450 4500);
FORCEPROP 2 LAST SIG_NAME VR_PVNN_PCH_VDD
R 1
J 0
(-10475 4665);
DISPLAY 0.617021 (-10475 4665);
PAINT ORANGE (-10475 4665);
FORCEPROP 2 LASTPROP $XRERR UNIQUE?
J 0
(-10715 4665);
DISPLAY 0.638298 (-10715 4665);
PAINT MONO (-10715 4665);
DISPLAY INVISIBLE (-10715 4665);
WIRE 16 -1 (-10450 4500)(-10175 4500);
WIRE 16 -1 (-10175 4350)(-11975 4350);
WIRE 16 -1 (-11975 4650)(-11975 4350);
WIRE 16 -1 (-11975 4350)(-12800 4350);
FORCEPROP 2 LAST SIG_NAME VR_PVNN_PCH_AIREF1
J 0
(-12750 4365);
DISPLAY 0.617021 (-12750 4365);
PAINT ORANGE (-12750 4365);
WIRE 16 -1 (-12250 4650)(-11975 4650);
WIRE 16 -1 (-11175 4150)(-10175 4150);
FORCEPROP 2 LAST SIG_NAME VR_PVNN_PCH_VREN
J 0
(-11125 4165);
DISPLAY 0.617021 (-11125 4165);
PAINT ORANGE (-11125 4165);
FORCEPROP 2 LASTPROP $XRERR UNIQUE?
J 0
(-11365 4165);
DISPLAY 0.638298 (-11365 4165);
PAINT MONO (-11365 4165);
DISPLAY INVISIBLE (-11365 4165);
WIRE 16 -1 (-11175 4150)(-11175 4975);
WIRE 16 -1 (-11700 4150)(-11175 4150);
WIRE 16 -1 (-10175 4450)(-10750 4450);
FORCEPROP 2 LAST SIG_NAME TP_PVNN_PCH_VCLK
J 0
(-10750 4465);
DISPLAY 0.617021 (-10750 4465);
PAINT ORANGE (-10750 4465);
FORCEPROP 2 LASTPROP $XRERR UNIQUE?
J 0
(-10990 4450);
DISPLAY 0.638298 (-10990 4450);
PAINT MONO (-10990 4450);
DISPLAY INVISIBLE (-10990 4450);
WIRE 16 -1 (-8525 4700)(-8525 3800);
WIRE 16 -1 (-9275 3800)(-8525 3800);
FORCEPROP 2 LAST SIG_NAME PU_VR_PVNN_PCH_FAULT1
J 0
(-9175 3815);
DISPLAY 0.617021 (-9175 3815);
PAINT ORANGE (-9175 3815);
FORCEPROP 2 LASTPROP $XRERR UNIQUE?
J 0
(-9415 3815);
DISPLAY 0.638298 (-9415 3815);
PAINT MONO (-9415 3815);
DISPLAY INVISIBLE (-9415 3815);
WIRE 16 -1 (-9275 3700)(-8475 3700);
FORCEPROP 2 LAST SIG_NAME TP_PVNN_PCH_MP2
J 0
(-9100 3715);
DISPLAY 0.617021 (-9100 3715);
PAINT ORANGE (-9100 3715);
FORCEPROP 2 LASTPROP $XRERR UNIQUE?
J 0
(-8445 3700);
DISPLAY 0.638298 (-8445 3700);
PAINT MONO (-8445 3700);
DISPLAY INVISIBLE (-8445 3700);
WIRE 16 -1 (-9275 3750)(-8475 3750);
FORCEPROP 2 LAST SIG_NAME TP_PVNN_PCH_MP3
J 0
(-9100 3765);
DISPLAY 0.617021 (-9100 3765);
PAINT ORANGE (-9100 3765);
FORCEPROP 2 LASTPROP $XRERR UNIQUE?
J 0
(-8445 3750);
DISPLAY 0.638298 (-8445 3750);
PAINT MONO (-8445 3750);
DISPLAY INVISIBLE (-8445 3750);
WIRE 16 -1 (-9275 3450)(-8475 3450);
FORCEPROP 2 LAST SIG_NAME NC_PVNN_PCH_DNC3
J 0
(-9175 3465);
DISPLAY 0.617021 (-9175 3465);
PAINT ORANGE (-9175 3465);
FORCEPROP 2 LASTPROP $XRERR UNIQUE?
J 0
(-8445 3450);
DISPLAY 0.638298 (-8445 3450);
PAINT MONO (-8445 3450);
DISPLAY INVISIBLE (-8445 3450);
WIRE 16 -1 (-8625 4050)(-9275 4050);
FORCEPROP 2 LAST SIG_NAME TP_PVNN_PCH_SVID_ALERT
J 0
(-9175 4065);
DISPLAY 0.617021 (-9175 4065);
PAINT ORANGE (-9175 4065);
FORCEPROP 2 LASTPROP $XRERR UNIQUE?
J 0
(-8595 4050);
DISPLAY 0.638298 (-8595 4050);
PAINT MONO (-8595 4050);
DISPLAY INVISIBLE (-8595 4050);
WIRE 16 -1 (-9275 3500)(-8475 3500);
FORCEPROP 2 LAST SIG_NAME NC_PVNN_PCH_DNC4
J 0
(-9175 3515);
DISPLAY 0.617021 (-9175 3515);
PAINT ORANGE (-9175 3515);
FORCEPROP 2 LASTPROP $XRERR UNIQUE?
J 0
(-8445 3500);
DISPLAY 0.638298 (-8445 3500);
PAINT MONO (-8445 3500);
DISPLAY INVISIBLE (-8445 3500);
WIRE 16 -1 (-9275 3400)(-8475 3400);
FORCEPROP 2 LAST SIG_NAME NC_PVNN_PCH_DNC2
J 0
(-9175 3415);
DISPLAY 0.617021 (-9175 3415);
PAINT ORANGE (-9175 3415);
FORCEPROP 2 LASTPROP $XRERR UNIQUE?
J 0
(-8445 3400);
DISPLAY 0.638298 (-8445 3400);
PAINT MONO (-8445 3400);
DISPLAY INVISIBLE (-8445 3400);
WIRE 16 -1 (-9275 3350)(-8475 3350);
FORCEPROP 2 LAST SIG_NAME NC_PVNN_PCH_DNC1
J 0
(-9175 3365);
DISPLAY 0.617021 (-9175 3365);
PAINT ORANGE (-9175 3365);
FORCEPROP 2 LASTPROP $XRERR UNIQUE?
J 0
(-8445 3350);
DISPLAY 0.638298 (-8445 3350);
PAINT MONO (-8445 3350);
DISPLAY INVISIBLE (-8445 3350);
WIRE 16 -1 (-9275 3300)(-8450 3300);
FORCEPROP 2 LAST SIG_NAME NC_PVNN_PCH_DNC0
J 0
(-9175 3315);
DISPLAY 0.617021 (-9175 3315);
PAINT ORANGE (-9175 3315);
FORCEPROP 2 LASTPROP $XRERR UNIQUE?
J 0
(-8420 3300);
DISPLAY 0.638298 (-8420 3300);
PAINT MONO (-8420 3300);
DISPLAY INVISIBLE (-8420 3300);
WIRE 16 -1 (-11850 3500)(-10175 3500);
WIRE 16 -1 (-11850 2225)(-11850 3500);
WIRE 16 -1 (-12475 2225)(-11850 2225);
FORCEPROP 2 LAST SIG_NAME VR_P1V05_PCH_STBY_AVSP
J 0
(-12390 2240);
DISPLAY 0.617021 (-12390 2240);
PAINT ORANGE (-12390 2240);
FORCEPROP 2 LASTPROP $XRERR UNIQUE?
J 0
(-12630 2240);
DISPLAY 0.638298 (-12630 2240);
PAINT MONO (-12630 2240);
DISPLAY INVISIBLE (-12630 2240);
WIRE 16 -1 (-12475 2175)(-12475 2225);
WIRE 16 -1 (-12575 2225)(-12475 2225);
WIRE 16 -1 (-10175 3550)(-11925 3550);
WIRE 16 -1 (-11925 2475)(-11925 3550);
WIRE 16 -1 (-12375 2475)(-11925 2475);
WIRE 16 -1 (-12375 2500)(-12375 2475);
WIRE 16 -1 (-13275 2475)(-12375 2475);
FORCEPROP 2 LAST SIG_NAME VSENSE_PVNN_PCH_STBY_AVSN
J 0
(-13290 2490);
DISPLAY 0.617021 (-13290 2490);
PAINT ORANGE (-13290 2490);
WIRE 16 -1 (-10175 3600)(-11975 3600);
WIRE 16 -1 (-11975 2750)(-11975 3600);
WIRE 16 -1 (-12375 2750)(-11975 2750);
WIRE 16 -1 (-12375 2700)(-12375 2750);
WIRE 16 -1 (-12575 2750)(-12375 2750);
FORCEPROP 2 LAST SIG_NAME VR_PVNN_PCH_AVSP
J 0
(-12515 2765);
DISPLAY 0.617021 (-12515 2765);
PAINT ORANGE (-12515 2765);
FORCEPROP 2 LASTPROP $XRERR UNIQUE?
J 0
(-12755 2765);
DISPLAY 0.638298 (-12755 2765);
PAINT MONO (-12755 2765);
DISPLAY INVISIBLE (-12755 2765);
WIRE 16 -1 (-11800 3450)(-10175 3450);
WIRE 16 -1 (-11800 1950)(-11800 3450);
WIRE 16 -1 (-11800 1950)(-12475 1950);
WIRE 16 -1 (-12475 1975)(-12475 1950);
WIRE 16 -1 (-12475 1950)(-13175 1950);
FORCEPROP 2 LAST SIG_NAME VSENSE_P1V05_PCH_STBY_AVSN
J 0
(-13190 1965);
DISPLAY 0.617021 (-13190 1965);
PAINT ORANGE (-13190 1965);
WIRE 16 -1 (-11250 3100)(-10175 3100);
WIRE 16 -1 (-11250 3100)(-11250 2925);
WIRE 16 -1 (-12525 3100)(-11250 3100);
FORCEPROP 2 LAST SIG_NAME VR_P1V05_PCH_BIREF1
J 2
(-12120 3100);
DISPLAY 0.617021 (-12120 3100);
PAINT ORANGE (-12120 3100);
WIRE 16 -1 (-11425 2925)(-11250 2925);
WIRE 16 -1 (-10175 4000)(-11100 4000);
FORCEPROP 2 LAST SIG_NAME TP_VR_PVNN_PCH_AIINSEN
J 0
(-11100 4010);
DISPLAY 0.617021 (-11100 4010);
PAINT ORANGE (-11100 4010);
FORCEPROP 2 LASTPROP $XRERR UNIQUE?
J 0
(-11340 4000);
DISPLAY 0.638298 (-11340 4000);
PAINT MONO (-11340 4000);
DISPLAY INVISIBLE (-11340 4000);
WIRE 16 -1 (-10375 2950)(-10175 2950);
WIRE 16 -1 (-10375 2375)(-10375 2950);
FORCEPROP 0 LAST SIG_NAME VR_PVNN_PCH_XADDR2
R 1
J 0
(-10385 2410);
DISPLAY 0.617021 (-10385 2410);
PAINT ORANGE (-10385 2410);
FORCEPROP 2 LASTPROP $XRERR UNIQUE?
J 0
(-10625 2410);
DISPLAY 0.638298 (-10625 2410);
PAINT MONO (-10625 2410);
DISPLAY INVISIBLE (-10625 2410);
WIRE 16 -1 (-10750 3000)(-10175 3000);
WIRE 16 -1 (-10750 2350)(-10750 3000);
FORCEPROP 0 LAST SIG_NAME VR_PVNN_PCH_XADDR1
R 1
J 0
(-10760 2385);
DISPLAY 0.617021 (-10760 2385);
PAINT ORANGE (-10760 2385);
FORCEPROP 2 LASTPROP $XRERR UNIQUE?
J 0
(-11000 2385);
DISPLAY 0.638298 (-11000 2385);
PAINT MONO (-11000 2385);
DISPLAY INVISIBLE (-11000 2385);
WIRE 16 -1 (-10975 3700)(-10175 3700);
FORCEPROP 2 LAST SIG_NAME TP_PVNN_PCH_RESET_N
J 0
(-10875 3715);
DISPLAY 0.617021 (-10875 3715);
PAINT ORANGE (-10875 3715);
FORCEPROP 2 LASTPROP $XRERR UNIQUE?
J 0
(-11215 3700);
DISPLAY 0.638298 (-11215 3700);
PAINT MONO (-11215 3700);
DISPLAY INVISIBLE (-11215 3700);
WIRE 16 -1 (-10975 3850)(-10175 3850);
FORCEPROP 2 LAST SIG_NAME TP_PVNN_PCH_VDIO
J 0
(-10875 3865);
DISPLAY 0.617021 (-10875 3865);
PAINT ORANGE (-10875 3865);
FORCEPROP 2 LASTPROP $XRERR UNIQUE?
J 0
(-11215 3850);
DISPLAY 0.638298 (-11215 3850);
PAINT MONO (-11215 3850);
DISPLAY INVISIBLE (-11215 3850);
WIRE 16 -1 (-11300 3300)(-10175 3300);
FORCEPROP 2 LAST SIG_NAME SMB_VR_SCL_PVNN_PCH
J 0
(-10875 3315);
DISPLAY 0.617021 (-10875 3315);
PAINT ORANGE (-10875 3315);
FORCEPROP 2 LASTPROP $XRERR UNIQUE?
J 0
(-11115 3315);
DISPLAY 0.638298 (-11115 3315);
PAINT MONO (-11115 3315);
DISPLAY INVISIBLE (-11115 3315);
WIRE 16 -1 (-10975 3350)(-10175 3350);
FORCEPROP 2 LAST SIG_NAME SMB_VR_SDA_PVNN_PCH
J 0
(-10875 3365);
DISPLAY 0.617021 (-10875 3365);
PAINT ORANGE (-10875 3365);
FORCEPROP 2 LASTPROP $XRERR UNIQUE?
J 0
(-11115 3365);
DISPLAY 0.638298 (-11115 3365);
PAINT MONO (-11115 3365);
DISPLAY INVISIBLE (-11115 3365);
WIRE 16 -1 (-12525 4300)(-10175 4300);
FORCEPROP 2 LAST SIG_NAME ISENSE_PVNN_PCH_PH1_IMON
J 2
(-11802 4318);
DISPLAY 0.617021 (-11802 4318);
PAINT ORANGE (-11802 4318);
WIRE 16 -1 (-12525 4150)(-11900 4150);
FORCEPROP 2 LAST SIG_NAME PWRGD_P1V8_PCH_STBY
J 0
(-12525 4165);
DISPLAY 0.617021 (-12525 4165);
PAINT ORANGE (-12525 4165);
WIRE 16 -1 (-12525 4200)(-10175 4200);
FORCEPROP 2 LAST SIG_NAME A_TSENSE_PVNN_PCH_TMON
J 2
(-11973 4220);
DISPLAY 0.617021 (-11973 4220);
PAINT ORANGE (-11973 4220);
WIRE 16 -1 (-10175 4050)(-12525 4050);
FORCEPROP 2 LAST SIG_NAME VR_PVNN_PCH_VINSEN
J 0
(-12550 4065);
DISPLAY 0.617021 (-12550 4065);
PAINT ORANGE (-12550 4065);
WIRE 16 -1 (-10175 3900)(-12525 3900);
FORCEPROP 2 LAST SIG_NAME VR_PVNN_P1V05_PCH_VD12
J 0
(-12550 3915);
DISPLAY 0.617021 (-12550 3915);
PAINT ORANGE (-12550 3915);
WIRE 16 -1 (-12525 3300)(-11500 3300);
FORCEPROP 2 LAST SIG_NAME SMB_VR_STBY_LVC3_SCL
J 0
(-12550 3315);
DISPLAY 0.617021 (-12550 3315);
PAINT ORANGE (-12550 3315);
WIRE 16 -1 (-12525 3350)(-11175 3350);
FORCEPROP 2 LAST SIG_NAME SMB_VR_STBY_LVC3_SDA
J 0
(-12550 3365);
DISPLAY 0.617021 (-12550 3365);
PAINT ORANGE (-12550 3365);
WIRE 16 -1 (-12525 3050)(-10175 3050);
FORCEPROP 2 LAST SIG_NAME ISENSE_P1V05_PCH_STBY_PH1_IMON
J 2
(-11905 3049);
DISPLAY 0.617021 (-11905 3049);
PAINT ORANGE (-11905 3049);
WIRE 16 -1 (-12975 3200)(-10175 3200);
FORCEPROP 2 LAST SIG_NAME A_TSENSE_P1V05_PCH_STBY_TMON
J 2
(-12224 3216);
DISPLAY 0.617021 (-12224 3216);
PAINT ORANGE (-12224 3216);
WIRE 16 -1 (-12550 2925)(-11625 2925);
FORCEPROP 2 LAST SIG_NAME VR_PVNN_P1V05_PCH_VD12
J 2
(-12070 2925);
DISPLAY 0.617021 (-12070 2925);
PAINT ORANGE (-12070 2925);
WIRE 16 -1 (-12450 4650)(-13275 4650);
FORCEPROP 2 LAST SIG_NAME VR_PVNN_P1V05_PCH_VD12
J 0
(-13150 4665);
DISPLAY 0.617021 (-13150 4665);
PAINT ORANGE (-13150 4665);
WIRE 16 -1 (-12775 2225)(-13300 2225);
FORCEPROP 2 LAST SIG_NAME VSENSE_P1V05_PCH_STBY_AVSP
J 0
(-13315 2240);
DISPLAY 0.617021 (-13315 2240);
PAINT ORANGE (-13315 2240);
WIRE 16 -1 (-12775 2750)(-13350 2750);
FORCEPROP 2 LAST SIG_NAME VSENSE_PVNN_PCH_STBY_AVSP
J 0
(-13315 2765);
DISPLAY 0.617021 (-13315 2765);
PAINT ORANGE (-13315 2765);
DOT 1 (-12475 1950);
DOT 1 (-12475 2225);
DOT 1 (-12375 2475);
DOT 1 (-12375 2750);
DOT 1 (-12550 5350);
DOT 1 (-12325 5350);
DOT 1 (-10750 1975);
DOT 1 (-11250 3100);
DOT 1 (-8800 2150);
DOT 1 (-8900 3050);
DOT 1 (-8900 3000);
DOT 1 (-11975 4350);
DOT 1 (-11175 4150);
DOT 1 (-10450 5225);
DOT 1 (-10450 5600);
DOT 1 (-10150 5225);
DOT 1 (-9025 4500);
DOT 1 (-8525 5175);
DOT 1 (-8375 5175);
DOT 1 (-8200 5175);
DOT 1 (-7775 3650);
DOT 1 (-7450 3600);
DOT 1 (-8000 4500);
DOT 1 (-7775 5175);
FORCENOTE
PVNN_PCH SPEC:
(-6825 5850) 0;
DISPLAY LEFT (-6825 5850);
DISPLAY 0.808511 (-6825 5850);
PAINT PURPLE (-6825 5850);
FORCENOTE
ROOM=PVNN_PCH_STBY
(-13550 1250) 0;
DISPLAY LEFT (-13550 1250);
DISPLAY 1.595745 (-13550 1250);
PAINT PURPLE (-13550 1250);
FORCENOTE
VERIFY
(-7250 2300) 0;
DISPLAY LEFT (-7250 2300);
DISPLAY 1.021277 (-7250 2300);
PAINT PURPLE (-7250 2300);
FORCENOTE
SW FREQ: 625KHZ
(-7814 5399) 0;
DISPLAY LEFT (-7814 5399);
DISPLAY 0.808511 (-7814 5399);
PAINT PURPLE (-7814 5399);
FORCENOTE
P1V05_PCH SPEC:
(-7825 5850) 0;
DISPLAY LEFT (-7825 5850);
DISPLAY 0.808511 (-7825 5850);
PAINT PURPLE (-7825 5850);
FORCENOTE
VOUT=1.05V
(-7825 5775) 0;
DISPLAY LEFT (-7825 5775);
DISPLAY 0.808511 (-7825 5775);
PAINT PURPLE (-7825 5775);
FORCENOTE
DC TOL= +/-1.5%
(-7800 5525) 0;
DISPLAY LEFT (-7800 5525);
DISPLAY 0.808511 (-7800 5525);
PAINT PURPLE (-7800 5525);
FORCENOTE
TDC=11.4A
(-7825 5725) 0;
DISPLAY LEFT (-7825 5725);
DISPLAY 0.808511 (-7825 5725);
PAINT PURPLE (-7825 5725);
FORCENOTE
PK=15.9A
(-7800 5675) 0;
DISPLAY LEFT (-7800 5675);
DISPLAY 0.808511 (-7800 5675);
PAINT PURPLE (-7800 5675);
FORCENOTE
STEP=TBD
(-7800 5625) 0;
DISPLAY LEFT (-7800 5625);
DISPLAY 0.808511 (-7800 5625);
PAINT PURPLE (-7800 5625);
FORCENOTE
STEP RATE=TBDA/US
(-7800 5575) 0;
DISPLAY LEFT (-7800 5575);
DISPLAY 0.808511 (-7800 5575);
PAINT PURPLE (-7800 5575);
FORCENOTE
AC TOL + RIPPLE=+/-3.0%
(-7800 5475) 0;
DISPLAY LEFT (-7800 5475);
DISPLAY 0.808511 (-7800 5475);
PAINT PURPLE (-7800 5475);
FORCENOTE
DC TOL= +/-1.5%
(-6775 5525) 0;
DISPLAY LEFT (-6775 5525);
DISPLAY 0.808511 (-6775 5525);
PAINT PURPLE (-6775 5525);
FORCENOTE
SW FREQ: 500KHZ
(-6779 5402) 0;
DISPLAY LEFT (-6779 5402);
DISPLAY 0.808511 (-6779 5402);
PAINT PURPLE (-6779 5402);
FORCENOTE
STEP=TBD
(-6775 5625) 0;
DISPLAY LEFT (-6775 5625);
DISPLAY 0.808511 (-6775 5625);
PAINT PURPLE (-6775 5625);
FORCENOTE
PK=19.5A
(-6775 5675) 0;
DISPLAY LEFT (-6775 5675);
DISPLAY 0.808511 (-6775 5675);
PAINT PURPLE (-6775 5675);
FORCENOTE
TDC=16A
(-6800 5725) 0;
DISPLAY LEFT (-6800 5725);
DISPLAY 0.808511 (-6800 5725);
PAINT PURPLE (-6800 5725);
FORCENOTE
STEP RATE=TBDA/US
(-6775 5575) 0;
DISPLAY LEFT (-6775 5575);
DISPLAY 0.808511 (-6775 5575);
PAINT PURPLE (-6775 5575);
FORCENOTE
VOUT=0.85V TO 1.0V
(-6800 5775) 0;
DISPLAY LEFT (-6800 5775);
DISPLAY 0.808511 (-6800 5775);
PAINT PURPLE (-6800 5775);
FORCENOTE
AC TOL + RIPPLE=+/-3.0%
(-6775 5475) 0;
DISPLAY LEFT (-6775 5475);
DISPLAY 0.808511 (-6775 5475);
PAINT PURPLE (-6775 5475);
QUIT
